(lib_symbols
	(symbol "antmicroBarrelPowerConnectors:BarrelJack_Pin2mm_MJ-179PH"
			(pin_names
				(hide yes)
			)
			(exclude_from_sim no)
			(in_bom yes)
			(on_board yes)
			(property "Reference" "J"
				(at 17.78 -5.08 0)
				(effects
					(font
						(size 1.27 1.27)
						(thickness 0.15)
					)
					(justify left bottom)
				)
			)
			(property "Value" "BarrelJack_3167288"
				(at 17.78 -7.62 0)
				(effects
					(font
						(size 1.27 1.27)
						(thickness 0.15)
					)
					(justify left bottom)
				)
			)
			(property "Footprint" "antmicro-footprints:BarrelJack_Pin2mm_MJ-179PH"
				(at 17.78 -10.16 0)
				(effects
					(font
						(size 1.27 1.27)
						(thickness 0.15)
					)
					(justify left bottom)
					(hide yes)
				)
			)
			(property "Datasheet" "https://www.farnell.com/datasheets/3167288.pdf"
				(at 17.78 -12.7 0)
				(effects
					(font
						(size 1.27 1.27)
						(thickness 0.15)
					)
					(justify left bottom)
					(hide yes)
				)
			)
			(property "Description" "DC Power Connector, Jack, 4 A, 1.95 mm, PCB Mount, Through Hole"
				(at 0 0 0)
				(effects
					(font
						(size 1.27 1.27)
					)
					(hide yes)
				)
			)
			(property "Manufacturer" "Multicomp Pro"
				(at 17.78 -15.24 0)
				(effects
					(font
						(size 1.27 1.27)
						(thickness 0.15)
					)
					(justify left bottom)
					(hide yes)
				)
			)
			(property "MPN" "MJ-179PH"
				(at 17.78 -17.78 0)
				(effects
					(font
						(size 1.27 1.27)
						(thickness 0.15)
					)
					(justify left bottom)
					(hide yes)
				)
			)
			(property "Author" "Antmicro"
				(at 17.78 -20.32 0)
				(effects
					(font
						(size 1.27 1.27)
						(thickness 0.15)
					)
					(justify left bottom)
					(hide yes)
				)
			)
			(property "License" "Apache-2.0"
				(at 17.78 -22.86 0)
				(effects
					(font
						(size 1.27 1.27)
						(thickness 0.15)
					)
					(justify left bottom)
					(hide yes)
				)
			)
			(property "ki_keywords" "HORIZONTAL, THT, JACK, CONNECTOR, POWER"
				(at 0 0 0)
				(effects
					(font
						(size 1.27 1.27)
					)
					(hide yes)
				)
			)
			(symbol "BarrelJack_Pin2mm_MJ-179PH_0_1"
				(polyline
					(pts
						(xy 5.08 -5.08) (xy 5.334 -4.064) (xy 4.826 -4.064) (xy 5.08 -5.08)
					)
					(stroke
						(width 0)
						(type default)
					)
					(fill
						(type outline)
					)
				)
			)
			(symbol "BarrelJack_Pin2mm_MJ-179PH_1_1"
				(polyline
					(pts
						(xy 2.54 0) (xy 6.985 0)
					)
					(stroke
						(width 0.254)
						(type default)
					)
					(fill
						(type background)
					)
				)
				(polyline
					(pts
						(xy 2.54 -2.54) (xy 5.08 -2.54)
					)
					(stroke
						(width 0.254)
						(type default)
					)
					(fill
						(type background)
					)
				)
				(polyline
					(pts
						(xy 2.54 -5.08) (xy 6.985 -5.08)
					)
					(stroke
						(width 0.254)
						(type default)
					)
					(fill
						(type background)
					)
				)
				(rectangle
					(start 2.54 -6.35)
					(end 12.7 1.27)
					(stroke
						(width 0.254)
						(type default)
					)
					(fill
						(type background)
					)
				)
				(polyline
					(pts
						(xy 5.08 -2.54) (xy 5.08 -5.08)
					)
					(stroke
						(width 0.254)
						(type default)
					)
					(fill
						(type background)
					)
				)
				(rectangle
					(start 6.985 0.635)
					(end 10.16 -0.635)
					(stroke
						(width 0.254)
						(type default)
					)
					(fill
						(type outline)
					)
				)
				(arc
					(start 6.985 -5.08)
					(mid 7.543 -3.733)
					(end 8.89 -3.175)
					(stroke
						(width 0.254)
						(type default)
					)
					(fill
						(type none)
					)
				)
				(arc
					(start 8.89 -3.175)
					(mid 10.237 -3.733)
					(end 10.795 -5.08)
					(stroke
						(width 0.254)
						(type default)
					)
					(fill
						(type none)
					)
				)
				(arc
					(start 10.16 0.635)
					(mid 10.609 0.449)
					(end 10.795 0)
					(stroke
						(width 0.254)
						(type default)
					)
					(fill
						(type outline)
					)
				)
				(arc
					(start 10.795 0)
					(mid 10.609 -0.449)
					(end 10.16 -0.635)
					(stroke
						(width 0.254)
						(type default)
					)
					(fill
						(type outline)
					)
				)
				(pin passive line
					(at 0 0 0)
					(length 2.54)
					(name "1"
						(effects
							(font
								(size 1.27 1.27)
							)
						)
					)
					(number "1"
						(effects
							(font
								(size 1.27 1.27)
							)
						)
					)
				)
				(pin passive line
					(at 0 -2.54 0)
					(length 2.54)
					(name "2"
						(effects
							(font
								(size 1.27 1.27)
							)
						)
					)
					(number "2"
						(effects
							(font
								(size 1.27 1.27)
							)
						)
					)
				)
				(pin passive line
					(at 0 -5.08 0)
					(length 2.54)
					(name "3"
						(effects
							(font
								(size 1.27 1.27)
							)
						)
					)
					(number "3"
						(effects
							(font
								(size 1.27 1.27)
							)
						)
					)
				)
			)
		)
	(symbol "antmicroCapacitors0402:C_100n_16V_X7R_0402"
			(pin_numbers
				(hide yes)
			)
			(pin_names
				(hide yes)
			)
			(exclude_from_sim no)
			(in_bom yes)
			(on_board yes)
			(property "Reference" "C"
				(at 15.24 -5.08 0)
				(effects
					(font
						(size 1.27 1.27)
						(thickness 0.15)
					)
					(justify left bottom)
				)
			)
			(property "Value" "C_100n_16V_X7R_0402"
				(at 15.24 -22.86 0)
				(effects
					(font
						(size 1.27 1.27)
						(thickness 0.15)
					)
					(justify left bottom)
					(hide yes)
				)
			)
			(property "Footprint" "antmicro-footprints:C_0402_1005Metric"
				(at 15.24 -25.4 0)
				(effects
					(font
						(size 1.27 1.27)
						(thickness 0.15)
					)
					(justify left bottom)
					(hide yes)
				)
			)
			(property "Datasheet" "https://www.kemet.com/en/us/capacitors/product/C0402C104J4RAC7411.html"
				(at 15.24 -27.94 0)
				(effects
					(font
						(size 1.27 1.27)
						(thickness 0.15)
					)
					(justify left bottom)
					(hide yes)
				)
			)
			(property "Description" "SMD Multilayer Ceramic Capacitor, 100nF, 50V, 0402, ±5%, X7R"
				(at 15.24 -33.02 0)
				(effects
					(font
						(size 1.27 1.27)
					)
					(justify left bottom)
					(hide yes)
				)
			)
			(property "MPN" "C0402C104J4RAC7411"
				(at 15.24 -30.48 0)
				(effects
					(font
						(size 1.27 1.27)
						(thickness 0.15)
					)
					(justify left bottom)
					(hide yes)
				)
			)
			(property "Val" "100n"
				(at 15.24 -7.62 0)
				(effects
					(font
						(size 1.27 1.27)
						(thickness 0.15)
					)
					(justify left bottom)
				)
			)
			(property "Voltage" "16V"
				(at 15.24 -10.16 0)
				(effects
					(font
						(size 1.27 1.27)
						(thickness 0.15)
					)
					(justify left bottom)
					(hide yes)
				)
			)
			(property "Dielectric" "X7R"
				(at 15.24 -12.7 0)
				(effects
					(font
						(size 1.27 1.27)
						(thickness 0.15)
					)
					(justify left bottom)
					(hide yes)
				)
			)
			(property "Manufacturer" "KEMET"
				(at 15.24 -15.24 0)
				(effects
					(font
						(size 1.27 1.27)
						(thickness 0.15)
					)
					(justify left bottom)
					(hide yes)
				)
			)
			(property "License" "Apache-2.0"
				(at 15.24 -17.78 0)
				(effects
					(font
						(size 1.27 1.27)
						(thickness 0.15)
					)
					(justify left bottom)
					(hide yes)
				)
			)
			(property "Author" "Antmicro"
				(at 15.24 -20.32 0)
				(effects
					(font
						(size 1.27 1.27)
						(thickness 0.15)
					)
					(justify left bottom)
					(hide yes)
				)
			)
			(property "ki_keywords" "SMT, CAPACITOR, PASSIVE"
				(at 0 0 0)
				(effects
					(font
						(size 1.27 1.27)
					)
					(hide yes)
				)
			)
			(symbol "C_100n_16V_X7R_0402_0_1"
				(polyline
					(pts
						(xy 2.032 -1.524) (xy 2.032 1.524)
					)
					(stroke
						(width 0.3048)
						(type default)
					)
					(fill
						(type none)
					)
				)
				(polyline
					(pts
						(xy 3.048 -1.524) (xy 3.048 1.524)
					)
					(stroke
						(width 0.3302)
						(type default)
					)
					(fill
						(type none)
					)
				)
			)
			(symbol "C_100n_16V_X7R_0402_1_1"
				(pin passive line
					(at 0 0 0)
					(length 2.032)
					(name "~"
						(effects
							(font
								(size 1.27 1.27)
							)
						)
					)
					(number "1"
						(effects
							(font
								(size 1.27 1.27)
							)
						)
					)
				)
				(pin passive line
					(at 5.08 0 180)
					(length 2.032)
					(name "~"
						(effects
							(font
								(size 1.27 1.27)
							)
						)
					)
					(number "2"
						(effects
							(font
								(size 1.27 1.27)
							)
						)
					)
				)
			)
		)
	(symbol "antmicroCapacitors0402:C_10n_0402"
			(pin_numbers
				(hide yes)
			)
			(pin_names
				(hide yes)
			)
			(exclude_from_sim no)
			(in_bom yes)
			(on_board yes)
			(property "Reference" "C"
				(at 20.32 -5.08 0)
				(effects
					(font
						(size 1.27 1.27)
						(thickness 0.15)
					)
					(justify left bottom)
				)
			)
			(property "Value" "C_10n_0402"
				(at 20.32 -10.16 0)
				(effects
					(font
						(size 1.27 1.27)
						(thickness 0.15)
					)
					(justify left bottom)
					(hide yes)
				)
			)
			(property "Footprint" "antmicro-footprints:C_0402_1005Metric"
				(at 20.32 -12.7 0)
				(effects
					(font
						(size 1.27 1.27)
						(thickness 0.15)
					)
					(justify left bottom)
					(hide yes)
				)
			)
			(property "Datasheet" "https://search.murata.co.jp/Ceramy/image/img/A01X/G101/ENG/GRM155R71H103KA88-01.pdf"
				(at 20.32 -15.24 0)
				(effects
					(font
						(size 1.27 1.27)
						(thickness 0.15)
					)
					(justify left bottom)
					(hide yes)
				)
			)
			(property "Description" ""
				(at 0 0 0)
				(effects
					(font
						(size 1.27 1.27)
					)
					(hide yes)
				)
			)
			(property "MPN" "GRM155R71H103KA88D"
				(at 20.32 -17.78 0)
				(effects
					(font
						(size 1.27 1.27)
						(thickness 0.15)
					)
					(justify left bottom)
					(hide yes)
				)
			)
			(property "Manufacturer" "Murata"
				(at 20.32 -20.32 0)
				(effects
					(font
						(size 1.27 1.27)
						(thickness 0.15)
					)
					(justify left bottom)
					(hide yes)
				)
			)
			(property "License" "Apache-2.0"
				(at 20.32 -22.86 0)
				(effects
					(font
						(size 1.27 1.27)
						(thickness 0.15)
					)
					(justify left bottom)
					(hide yes)
				)
			)
			(property "Author" "Antmicro"
				(at 20.32 -25.4 0)
				(effects
					(font
						(size 1.27 1.27)
						(thickness 0.15)
					)
					(justify left bottom)
					(hide yes)
				)
			)
			(property "Val" "10n"
				(at 20.32 -7.62 0)
				(effects
					(font
						(size 1.27 1.27)
						(thickness 0.15)
					)
					(justify left bottom)
				)
			)
			(property "Voltage" "50V"
				(at 20.32 -27.94 0)
				(effects
					(font
						(size 1.27 1.27)
					)
					(justify left bottom)
					(hide yes)
				)
			)
			(property "Dielectric" "X7R"
				(at 20.32 -30.48 0)
				(effects
					(font
						(size 1.27 1.27)
					)
					(justify left bottom)
					(hide yes)
				)
			)
			(symbol "C_10n_0402_0_1"
				(polyline
					(pts
						(xy 2.032 -1.524) (xy 2.032 1.524)
					)
					(stroke
						(width 0.3048)
						(type default)
					)
					(fill
						(type none)
					)
				)
				(polyline
					(pts
						(xy 3.048 -1.524) (xy 3.048 1.524)
					)
					(stroke
						(width 0.3302)
						(type default)
					)
					(fill
						(type none)
					)
				)
			)
			(symbol "C_10n_0402_1_1"
				(pin passive line
					(at 0 0 0)
					(length 2.032)
					(name "~"
						(effects
							(font
								(size 1.27 1.27)
							)
						)
					)
					(number "1"
						(effects
							(font
								(size 1.27 1.27)
							)
						)
					)
				)
				(pin passive line
					(at 5.08 0 180)
					(length 2.032)
					(name "~"
						(effects
							(font
								(size 1.27 1.27)
							)
						)
					)
					(number "2"
						(effects
							(font
								(size 1.27 1.27)
							)
						)
					)
				)
			)
		)
	(symbol "antmicroCapacitors0402:C_10u_0402"
			(pin_numbers
				(hide yes)
			)
			(pin_names
				(hide yes)
			)
			(exclude_from_sim no)
			(in_bom yes)
			(on_board yes)
			(property "Reference" "C"
				(at 20.32 -5.08 0)
				(effects
					(font
						(size 1.27 1.27)
						(thickness 0.15)
					)
					(justify left bottom)
				)
			)
			(property "Value" "C_10u_0402"
				(at 20.32 -10.16 0)
				(effects
					(font
						(size 1.27 1.27)
						(thickness 0.15)
					)
					(justify left bottom)
					(hide yes)
				)
			)
			(property "Footprint" "antmicro-footprints:C_0402_1005Metric"
				(at 20.32 -12.7 0)
				(effects
					(font
						(size 1.27 1.27)
						(thickness 0.15)
					)
					(justify left bottom)
					(hide yes)
				)
			)
			(property "Datasheet" ""
				(at 20.32 -15.24 0)
				(effects
					(font
						(size 1.27 1.27)
						(thickness 0.15)
					)
					(justify left bottom)
					(hide yes)
				)
			)
			(property "Description" ""
				(at 0 0 0)
				(effects
					(font
						(size 1.27 1.27)
					)
					(hide yes)
				)
			)
			(property "MPN" "CC0402MRX5R5BB106"
				(at 20.32 -17.78 0)
				(effects
					(font
						(size 1.27 1.27)
						(thickness 0.15)
					)
					(justify left bottom)
					(hide yes)
				)
			)
			(property "Manufacturer" "Yaego"
				(at 20.32 -20.32 0)
				(effects
					(font
						(size 1.27 1.27)
						(thickness 0.15)
					)
					(justify left bottom)
					(hide yes)
				)
			)
			(property "License" "Apache-2.0"
				(at 20.32 -22.86 0)
				(effects
					(font
						(size 1.27 1.27)
						(thickness 0.15)
					)
					(justify left bottom)
					(hide yes)
				)
			)
			(property "Author" "Antmicro"
				(at 20.32 -25.4 0)
				(effects
					(font
						(size 1.27 1.27)
						(thickness 0.15)
					)
					(justify left bottom)
					(hide yes)
				)
			)
			(property "Val" "10u"
				(at 20.32 -7.62 0)
				(effects
					(font
						(size 1.27 1.27)
						(thickness 0.15)
					)
					(justify left bottom)
				)
			)
			(property "Voltage" ""
				(at 20.32 -27.94 0)
				(effects
					(font
						(size 1.27 1.27)
					)
					(justify left bottom)
					(hide yes)
				)
			)
			(property "Dielectric" ""
				(at 20.32 -30.48 0)
				(effects
					(font
						(size 1.27 1.27)
					)
					(justify left bottom)
					(hide yes)
				)
			)
			(symbol "C_10u_0402_0_1"
				(polyline
					(pts
						(xy 2.032 -1.524) (xy 2.032 1.524)
					)
					(stroke
						(width 0.3048)
						(type default)
					)
					(fill
						(type none)
					)
				)
				(polyline
					(pts
						(xy 3.048 -1.524) (xy 3.048 1.524)
					)
					(stroke
						(width 0.3302)
						(type default)
					)
					(fill
						(type none)
					)
				)
			)
			(symbol "C_10u_0402_1_1"
				(pin passive line
					(at 0 0 0)
					(length 2.032)
					(name "~"
						(effects
							(font
								(size 1.27 1.27)
							)
						)
					)
					(number "1"
						(effects
							(font
								(size 1.27 1.27)
							)
						)
					)
				)
				(pin passive line
					(at 5.08 0 180)
					(length 2.032)
					(name "~"
						(effects
							(font
								(size 1.27 1.27)
							)
						)
					)
					(number "2"
						(effects
							(font
								(size 1.27 1.27)
							)
						)
					)
				)
			)
		)
	(symbol "antmicroCapacitors0402:C_18p_0402"
			(pin_numbers
				(hide yes)
			)
			(pin_names
				(hide yes)
			)
			(exclude_from_sim no)
			(in_bom yes)
			(on_board yes)
			(property "Reference" "C"
				(at 20.32 -5.08 0)
				(effects
					(font
						(size 1.27 1.27)
						(thickness 0.15)
					)
					(justify left bottom)
				)
			)
			(property "Value" "C_18p_0402"
				(at 20.32 -10.16 0)
				(effects
					(font
						(size 1.27 1.27)
						(thickness 0.15)
					)
					(justify left bottom)
					(hide yes)
				)
			)
			(property "Footprint" "antmicro-footprints:C_0402_1005Metric"
				(at 20.32 -12.7 0)
				(effects
					(font
						(size 1.27 1.27)
						(thickness 0.15)
					)
					(justify left bottom)
					(hide yes)
				)
			)
			(property "Datasheet" ""
				(at 20.32 -15.24 0)
				(effects
					(font
						(size 1.27 1.27)
						(thickness 0.15)
					)
					(justify left bottom)
					(hide yes)
				)
			)
			(property "Description" ""
				(at 0 0 0)
				(effects
					(font
						(size 1.27 1.27)
					)
					(hide yes)
				)
			)
			(property "MPN" "MC0402N180J500CT"
				(at 20.32 -17.78 0)
				(effects
					(font
						(size 1.27 1.27)
						(thickness 0.15)
					)
					(justify left bottom)
					(hide yes)
				)
			)
			(property "Manufacturer" "Multicomp"
				(at 20.32 -20.32 0)
				(effects
					(font
						(size 1.27 1.27)
						(thickness 0.15)
					)
					(justify left bottom)
					(hide yes)
				)
			)
			(property "License" "Apache-2.0"
				(at 20.32 -22.86 0)
				(effects
					(font
						(size 1.27 1.27)
						(thickness 0.15)
					)
					(justify left bottom)
					(hide yes)
				)
			)
			(property "Author" "Antmicro"
				(at 20.32 -25.4 0)
				(effects
					(font
						(size 1.27 1.27)
						(thickness 0.15)
					)
					(justify left bottom)
					(hide yes)
				)
			)
			(property "Val" "18p"
				(at 20.32 -7.62 0)
				(effects
					(font
						(size 1.27 1.27)
						(thickness 0.15)
					)
					(justify left bottom)
				)
			)
			(property "Voltage" ""
				(at 20.32 -27.94 0)
				(effects
					(font
						(size 1.27 1.27)
					)
					(justify left bottom)
					(hide yes)
				)
			)
			(property "Dielectric" ""
				(at 20.32 -30.48 0)
				(effects
					(font
						(size 1.27 1.27)
					)
					(justify left bottom)
					(hide yes)
				)
			)
			(symbol "C_18p_0402_0_1"
				(polyline
					(pts
						(xy 2.032 -1.524) (xy 2.032 1.524)
					)
					(stroke
						(width 0.3048)
						(type default)
					)
					(fill
						(type none)
					)
				)
				(polyline
					(pts
						(xy 3.048 -1.524) (xy 3.048 1.524)
					)
					(stroke
						(width 0.3302)
						(type default)
					)
					(fill
						(type none)
					)
				)
			)
			(symbol "C_18p_0402_1_1"
				(pin passive line
					(at 0 0 0)
					(length 2.032)
					(name "~"
						(effects
							(font
								(size 1.27 1.27)
							)
						)
					)
					(number "1"
						(effects
							(font
								(size 1.27 1.27)
							)
						)
					)
				)
				(pin passive line
					(at 5.08 0 180)
					(length 2.032)
					(name "~"
						(effects
							(font
								(size 1.27 1.27)
							)
						)
					)
					(number "2"
						(effects
							(font
								(size 1.27 1.27)
							)
						)
					)
				)
			)
		)
	(symbol "antmicroCapacitors0402:C_1n8_0402"
			(pin_numbers
				(hide yes)
			)
			(pin_names
				(hide yes)
			)
			(exclude_from_sim no)
			(in_bom yes)
			(on_board yes)
			(property "Reference" "C"
				(at 20.32 -5.08 0)
				(effects
					(font
						(size 1.27 1.27)
						(thickness 0.15)
					)
					(justify left bottom)
				)
			)
			(property "Value" "C_1n8_0402"
				(at 20.32 -10.16 0)
				(effects
					(font
						(size 1.27 1.27)
						(thickness 0.15)
					)
					(justify left bottom)
					(hide yes)
				)
			)
			(property "Footprint" "antmicro-footprints:C_0402_1005Metric"
				(at 20.32 -12.7 0)
				(effects
					(font
						(size 1.27 1.27)
						(thickness 0.15)
					)
					(justify left bottom)
					(hide yes)
				)
			)
			(property "Datasheet" ""
				(at 20.32 -15.24 0)
				(effects
					(font
						(size 1.27 1.27)
						(thickness 0.15)
					)
					(justify left bottom)
					(hide yes)
				)
			)
			(property "Description" ""
				(at 0 0 0)
				(effects
					(font
						(size 1.27 1.27)
					)
					(hide yes)
				)
			)
			(property "MPN" "0402B182K500CT"
				(at 20.32 -17.78 0)
				(effects
					(font
						(size 1.27 1.27)
						(thickness 0.15)
					)
					(justify left bottom)
					(hide yes)
				)
			)
			(property "Manufacturer" "Walsin"
				(at 20.32 -20.32 0)
				(effects
					(font
						(size 1.27 1.27)
						(thickness 0.15)
					)
					(justify left bottom)
					(hide yes)
				)
			)
			(property "License" "Apache-2.0"
				(at 20.32 -22.86 0)
				(effects
					(font
						(size 1.27 1.27)
						(thickness 0.15)
					)
					(justify left bottom)
					(hide yes)
				)
			)
			(property "Author" "Antmicro"
				(at 20.32 -25.4 0)
				(effects
					(font
						(size 1.27 1.27)
						(thickness 0.15)
					)
					(justify left bottom)
					(hide yes)
				)
			)
			(property "Val" "1n8"
				(at 20.32 -7.62 0)
				(effects
					(font
						(size 1.27 1.27)
						(thickness 0.15)
					)
					(justify left bottom)
				)
			)
			(property "Voltage" ""
				(at 20.32 -27.94 0)
				(effects
					(font
						(size 1.27 1.27)
					)
					(justify left bottom)
					(hide yes)
				)
			)
			(property "Dielectric" ""
				(at 20.32 -30.48 0)
				(effects
					(font
						(size 1.27 1.27)
					)
					(justify left bottom)
					(hide yes)
				)
			)
			(symbol "C_1n8_0402_0_1"
				(polyline
					(pts
						(xy 2.032 -1.524) (xy 2.032 1.524)
					)
					(stroke
						(width 0.3048)
						(type default)
					)
					(fill
						(type none)
					)
				)
				(polyline
					(pts
						(xy 3.048 -1.524) (xy 3.048 1.524)
					)
					(stroke
						(width 0.3302)
						(type default)
					)
					(fill
						(type none)
					)
				)
			)
			(symbol "C_1n8_0402_1_1"
				(pin passive line
					(at 0 0 0)
					(length 2.032)
					(name "~"
						(effects
							(font
								(size 1.27 1.27)
							)
						)
					)
					(number "1"
						(effects
							(font
								(size 1.27 1.27)
							)
						)
					)
				)
				(pin passive line
					(at 5.08 0 180)
					(length 2.032)
					(name "~"
						(effects
							(font
								(size 1.27 1.27)
							)
						)
					)
					(number "2"
						(effects
							(font
								(size 1.27 1.27)
							)
						)
					)
				)
			)
		)
	(symbol "antmicroCapacitors0402:C_1u_0402"
			(pin_numbers
				(hide yes)
			)
			(pin_names
				(hide yes)
			)
			(exclude_from_sim no)
			(in_bom yes)
			(on_board yes)
			(property "Reference" "C"
				(at 20.32 -5.08 0)
				(effects
					(font
						(size 1.27 1.27)
						(thickness 0.15)
					)
					(justify left bottom)
				)
			)
			(property "Value" "C_1u_0402"
				(at 20.32 -10.16 0)
				(effects
					(font
						(size 1.27 1.27)
						(thickness 0.15)
					)
					(justify left bottom)
					(hide yes)
				)
			)
			(property "Footprint" "antmicro-footprints:C_0402_1005Metric"
				(at 20.32 -12.7 0)
				(effects
					(font
						(size 1.27 1.27)
						(thickness 0.15)
					)
					(justify left bottom)
					(hide yes)
				)
			)
			(property "Datasheet" ""
				(at 20.32 -15.24 0)
				(effects
					(font
						(size 1.27 1.27)
						(thickness 0.15)
					)
					(justify left bottom)
					(hide yes)
				)
			)
			(property "Description" ""
				(at 0 0 0)
				(effects
					(font
						(size 1.27 1.27)
					)
					(hide yes)
				)
			)
			(property "MPN" "C1005X6S1A105K050BC"
				(at 20.32 -17.78 0)
				(effects
					(font
						(size 1.27 1.27)
						(thickness 0.15)
					)
					(justify left bottom)
					(hide yes)
				)
			)
			(property "Manufacturer" "TDK"
				(at 20.32 -20.32 0)
				(effects
					(font
						(size 1.27 1.27)
						(thickness 0.15)
					)
					(justify left bottom)
					(hide yes)
				)
			)
			(property "License" "Apache-2.0"
				(at 20.32 -22.86 0)
				(effects
					(font
						(size 1.27 1.27)
						(thickness 0.15)
					)
					(justify left bottom)
					(hide yes)
				)
			)
			(property "Author" "Antmicro"
				(at 20.32 -25.4 0)
				(effects
					(font
						(size 1.27 1.27)
						(thickness 0.15)
					)
					(justify left bottom)
					(hide yes)
				)
			)
			(property "Val" "1u"
				(at 20.32 -7.62 0)
				(effects
					(font
						(size 1.27 1.27)
						(thickness 0.15)
					)
					(justify left bottom)
				)
			)
			(property "Voltage" ""
				(at 20.32 -27.94 0)
				(effects
					(font
						(size 1.27 1.27)
					)
					(justify left bottom)
					(hide yes)
				)
			)
			(property "Dielectric" ""
				(at 20.32 -30.48 0)
				(effects
					(font
						(size 1.27 1.27)
					)
					(justify left bottom)
					(hide yes)
				)
			)
			(symbol "C_1u_0402_0_1"
				(polyline
					(pts
						(xy 2.032 -1.524) (xy 2.032 1.524)
					)
					(stroke
						(width 0.3048)
						(type default)
					)
					(fill
						(type none)
					)
				)
				(polyline
					(pts
						(xy 3.048 -1.524) (xy 3.048 1.524)
					)
					(stroke
						(width 0.3302)
						(type default)
					)
					(fill
						(type none)
					)
				)
			)
			(symbol "C_1u_0402_1_1"
				(pin passive line
					(at 0 0 0)
					(length 2.032)
					(name "~"
						(effects
							(font
								(size 1.27 1.27)
							)
						)
					)
					(number "1"
						(effects
							(font
								(size 1.27 1.27)
							)
						)
					)
				)
				(pin passive line
					(at 5.08 0 180)
					(length 2.032)
					(name "~"
						(effects
							(font
								(size 1.27 1.27)
							)
						)
					)
					(number "2"
						(effects
							(font
								(size 1.27 1.27)
							)
						)
					)
				)
			)
		)
	(symbol "antmicroCapacitors0402:C_22p_0402"
			(pin_numbers
				(hide yes)
			)
			(pin_names
				(hide yes)
			)
			(exclude_from_sim no)
			(in_bom yes)
			(on_board yes)
			(property "Reference" "C"
				(at 20.32 -5.08 0)
				(effects
					(font
						(size 1.27 1.27)
						(thickness 0.15)
					)
					(justify left bottom)
				)
			)
			(property "Value" "C_22p_0402"
				(at 20.32 -10.16 0)
				(effects
					(font
						(size 1.27 1.27)
						(thickness 0.15)
					)
					(justify left bottom)
					(hide yes)
				)
			)
			(property "Footprint" "antmicro-footprints:C_0402_1005Metric"
				(at 20.32 -12.7 0)
				(effects
					(font
						(size 1.27 1.27)
						(thickness 0.15)
					)
					(justify left bottom)
					(hide yes)
				)
			)
			(property "Datasheet" ""
				(at 20.32 -15.24 0)
				(effects
					(font
						(size 1.27 1.27)
						(thickness 0.15)
					)
					(justify left bottom)
					(hide yes)
				)
			)
			(property "Description" ""
				(at 0 0 0)
				(effects
					(font
						(size 1.27 1.27)
					)
					(hide yes)
				)
			)
			(property "MPN" "CC0402JRNPO9BN220"
				(at 20.32 -17.78 0)
				(effects
					(font
						(size 1.27 1.27)
						(thickness 0.15)
					)
					(justify left bottom)
					(hide yes)
				)
			)
			(property "Manufacturer" "Yaego"
				(at 20.32 -20.32 0)
				(effects
					(font
						(size 1.27 1.27)
						(thickness 0.15)
					)
					(justify left bottom)
					(hide yes)
				)
			)
			(property "License" "Apache-2.0"
				(at 20.32 -22.86 0)
				(effects
					(font
						(size 1.27 1.27)
						(thickness 0.15)
					)
					(justify left bottom)
					(hide yes)
				)
			)
			(property "Author" "Antmicro"
				(at 20.32 -25.4 0)
				(effects
					(font
						(size 1.27 1.27)
						(thickness 0.15)
					)
					(justify left bottom)
					(hide yes)
				)
			)
			(property "Val" "22p"
				(at 20.32 -7.62 0)
				(effects
					(font
						(size 1.27 1.27)
						(thickness 0.15)
					)
					(justify left bottom)
				)
			)
			(property "Voltage" ""
				(at 20.32 -27.94 0)
				(effects
					(font
						(size 1.27 1.27)
					)
					(justify left bottom)
					(hide yes)
				)
			)
			(property "Dielectric" ""
				(at 20.32 -30.48 0)
				(effects
					(font
						(size 1.27 1.27)
					)
					(justify left bottom)
					(hide yes)
				)
			)
			(symbol "C_22p_0402_0_1"
				(polyline
					(pts
						(xy 2.032 -1.524) (xy 2.032 1.524)
					)
					(stroke
						(width 0.3048)
						(type default)
					)
					(fill
						(type none)
					)
				)
				(polyline
					(pts
						(xy 3.048 -1.524) (xy 3.048 1.524)
					)
					(stroke
						(width 0.3302)
						(type default)
					)
					(fill
						(type none)
					)
				)
			)
			(symbol "C_22p_0402_1_1"
				(pin passive line
					(at 0 0 0)
					(length 2.032)
					(name "~"
						(effects
							(font
								(size 1.27 1.27)
							)
						)
					)
					(number "1"
						(effects
							(font
								(size 1.27 1.27)
							)
						)
					)
				)
				(pin passive line
					(at 5.08 0 180)
					(length 2.032)
					(name "~"
						(effects
							(font
								(size 1.27 1.27)
							)
						)
					)
					(number "2"
						(effects
							(font
								(size 1.27 1.27)
							)
						)
					)
				)
			)
		)
	(symbol "antmicroCapacitors0402:C_22u_0402"
			(pin_numbers
				(hide yes)
			)
			(pin_names
				(hide yes)
			)
			(exclude_from_sim no)
			(in_bom yes)
			(on_board yes)
			(property "Reference" "C"
				(at 20.32 -5.08 0)
				(effects
					(font
						(size 1.27 1.27)
						(thickness 0.15)
					)
					(justify left bottom)
				)
			)
			(property "Value" "C_22u_0402"
				(at 20.32 -10.16 0)
				(effects
					(font
						(size 1.27 1.27)
						(thickness 0.15)
					)
					(justify left bottom)
					(hide yes)
				)
			)
			(property "Footprint" "antmicro-footprints:C_0402_1005Metric"
				(at 20.32 -12.7 0)
				(effects
					(font
						(size 1.27 1.27)
						(thickness 0.15)
					)
					(justify left bottom)
					(hide yes)
				)
			)
			(property "Datasheet" ""
				(at 20.32 -15.24 0)
				(effects
					(font
						(size 1.27 1.27)
						(thickness 0.15)
					)
					(justify left bottom)
					(hide yes)
				)
			)
			(property "Description" ""
				(at 0 0 0)
				(effects
					(font
						(size 1.27 1.27)
					)
					(hide yes)
				)
			)
			(property "MPN" "04024W226MAT2A"
				(at 20.32 -17.78 0)
				(effects
					(font
						(size 1.27 1.27)
						(thickness 0.15)
					)
					(justify left bottom)
					(hide yes)
				)
			)
			(property "Manufacturer" "AVX"
				(at 20.32 -20.32 0)
				(effects
					(font
						(size 1.27 1.27)
						(thickness 0.15)
					)
					(justify left bottom)
					(hide yes)
				)
			)
			(property "License" "Apache-2.0"
				(at 20.32 -22.86 0)
				(effects
					(font
						(size 1.27 1.27)
						(thickness 0.15)
					)
					(justify left bottom)
					(hide yes)
				)
			)
			(property "Author" "Antmicro"
				(at 20.32 -25.4 0)
				(effects
					(font
						(size 1.27 1.27)
						(thickness 0.15)
					)
					(justify left bottom)
					(hide yes)
				)
			)
			(property "Val" "22u"
				(at 20.32 -7.62 0)
				(effects
					(font
						(size 1.27 1.27)
						(thickness 0.15)
					)
					(justify left bottom)
				)
			)
			(property "Voltage" ""
				(at 20.32 -27.94 0)
				(effects
					(font
						(size 1.27 1.27)
					)
					(justify left bottom)
					(hide yes)
				)
			)
			(property "Dielectric" ""
				(at 20.32 -30.48 0)
				(effects
					(font
						(size 1.27 1.27)
					)
					(justify left bottom)
					(hide yes)
				)
			)
			(symbol "C_22u_0402_0_1"
				(polyline
					(pts
						(xy 2.032 -1.524) (xy 2.032 1.524)
					)
					(stroke
						(width 0.3048)
						(type default)
					)
					(fill
						(type none)
					)
				)
				(polyline
					(pts
						(xy 3.048 -1.524) (xy 3.048 1.524)
					)
					(stroke
						(width 0.3302)
						(type default)
					)
					(fill
						(type none)
					)
				)
			)
			(symbol "C_22u_0402_1_1"
				(pin passive line
					(at 0 0 0)
					(length 2.032)
					(name "~"
						(effects
							(font
								(size 1.27 1.27)
							)
						)
					)
					(number "1"
						(effects
							(font
								(size 1.27 1.27)
							)
						)
					)
				)
				(pin passive line
					(at 5.08 0 180)
					(length 2.032)
					(name "~"
						(effects
							(font
								(size 1.27 1.27)
							)
						)
					)
					(number "2"
						(effects
							(font
								(size 1.27 1.27)
							)
						)
					)
				)
			)
		)
	(symbol "antmicroCapacitors0402:C_470n_0402"
			(pin_numbers
				(hide yes)
			)
			(pin_names
				(hide yes)
			)
			(exclude_from_sim no)
			(in_bom yes)
			(on_board yes)
			(property "Reference" "C"
				(at 20.32 -5.08 0)
				(effects
					(font
						(size 1.27 1.27)
						(thickness 0.15)
					)
					(justify left bottom)
				)
			)
			(property "Value" "C_470n_0402"
				(at 20.32 -10.16 0)
				(effects
					(font
						(size 1.27 1.27)
						(thickness 0.15)
					)
					(justify left bottom)
					(hide yes)
				)
			)
			(property "Footprint" "antmicro-footprints:C_0402_1005Metric"
				(at 20.32 -12.7 0)
				(effects
					(font
						(size 1.27 1.27)
						(thickness 0.15)
					)
					(justify left bottom)
					(hide yes)
				)
			)
			(property "Datasheet" ""
				(at 20.32 -15.24 0)
				(effects
					(font
						(size 1.27 1.27)
						(thickness 0.15)
					)
					(justify left bottom)
					(hide yes)
				)
			)
			(property "Description" ""
				(at 0 0 0)
				(effects
					(font
						(size 1.27 1.27)
					)
					(hide yes)
				)
			)
			(property "MPN" "C1005X5R1E474M050BB"
				(at 20.32 -17.78 0)
				(effects
					(font
						(size 1.27 1.27)
						(thickness 0.15)
					)
					(justify left bottom)
					(hide yes)
				)
			)
			(property "Manufacturer" "TDK"
				(at 20.32 -20.32 0)
				(effects
					(font
						(size 1.27 1.27)
						(thickness 0.15)
					)
					(justify left bottom)
					(hide yes)
				)
			)
			(property "License" "Apache-2.0"
				(at 20.32 -22.86 0)
				(effects
					(font
						(size 1.27 1.27)
						(thickness 0.15)
					)
					(justify left bottom)
					(hide yes)
				)
			)
			(property "Author" "Antmicro"
				(at 20.32 -25.4 0)
				(effects
					(font
						(size 1.27 1.27)
						(thickness 0.15)
					)
					(justify left bottom)
					(hide yes)
				)
			)
			(property "Val" "470n"
				(at 20.32 -7.62 0)
				(effects
					(font
						(size 1.27 1.27)
						(thickness 0.15)
					)
					(justify left bottom)
				)
			)
			(property "Voltage" ""
				(at 20.32 -27.94 0)
				(effects
					(font
						(size 1.27 1.27)
					)
					(justify left bottom)
					(hide yes)
				)
			)
			(property "Dielectric" ""
				(at 20.32 -30.48 0)
				(effects
					(font
						(size 1.27 1.27)
					)
					(justify left bottom)
					(hide yes)
				)
			)
			(symbol "C_470n_0402_0_1"
				(polyline
					(pts
						(xy 2.032 -1.524) (xy 2.032 1.524)
					)
					(stroke
						(width 0.3048)
						(type default)
					)
					(fill
						(type none)
					)
				)
				(polyline
					(pts
						(xy 3.048 -1.524) (xy 3.048 1.524)
					)
					(stroke
						(width 0.3302)
						(type default)
					)
					(fill
						(type none)
					)
				)
			)
			(symbol "C_470n_0402_1_1"
				(pin passive line
					(at 0 0 0)
					(length 2.032)
					(name "~"
						(effects
							(font
								(size 1.27 1.27)
							)
						)
					)
					(number "1"
						(effects
							(font
								(size 1.27 1.27)
							)
						)
					)
				)
				(pin passive line
					(at 5.08 0 180)
					(length 2.032)
					(name "~"
						(effects
							(font
								(size 1.27 1.27)
							)
						)
					)
					(number "2"
						(effects
							(font
								(size 1.27 1.27)
							)
						)
					)
				)
			)
		)
	(symbol "antmicroCapacitors0402:C_47p_0402"
			(pin_numbers
				(hide yes)
			)
			(pin_names
				(hide yes)
			)
			(exclude_from_sim no)
			(in_bom yes)
			(on_board yes)
			(property "Reference" "C"
				(at 20.32 -5.08 0)
				(effects
					(font
						(size 1.27 1.27)
						(thickness 0.15)
					)
					(justify left bottom)
				)
			)
			(property "Value" "C_47p_0402"
				(at 20.32 -10.16 0)
				(effects
					(font
						(size 1.27 1.27)
						(thickness 0.15)
					)
					(justify left bottom)
					(hide yes)
				)
			)
			(property "Footprint" "antmicro-footprints:C_0402_1005Metric"
				(at 20.32 -12.7 0)
				(effects
					(font
						(size 1.27 1.27)
						(thickness 0.15)
					)
					(justify left bottom)
					(hide yes)
				)
			)
			(property "Datasheet" ""
				(at 20.32 -15.24 0)
				(effects
					(font
						(size 1.27 1.27)
						(thickness 0.15)
					)
					(justify left bottom)
					(hide yes)
				)
			)
			(property "Description" ""
				(at 0 0 0)
				(effects
					(font
						(size 1.27 1.27)
					)
					(hide yes)
				)
			)
			(property "MPN" "GRM1555C1E470JA01D"
				(at 20.32 -17.78 0)
				(effects
					(font
						(size 1.27 1.27)
						(thickness 0.15)
					)
					(justify left bottom)
					(hide yes)
				)
			)
			(property "Manufacturer" "Murata"
				(at 20.32 -20.32 0)
				(effects
					(font
						(size 1.27 1.27)
						(thickness 0.15)
					)
					(justify left bottom)
					(hide yes)
				)
			)
			(property "License" "Apache-2.0"
				(at 20.32 -22.86 0)
				(effects
					(font
						(size 1.27 1.27)
						(thickness 0.15)
					)
					(justify left bottom)
					(hide yes)
				)
			)
			(property "Author" "Antmicro"
				(at 20.32 -25.4 0)
				(effects
					(font
						(size 1.27 1.27)
						(thickness 0.15)
					)
					(justify left bottom)
					(hide yes)
				)
			)
			(property "Val" "47p"
				(at 20.32 -7.62 0)
				(effects
					(font
						(size 1.27 1.27)
						(thickness 0.15)
					)
					(justify left bottom)
				)
			)
			(property "Voltage" ""
				(at 20.32 -27.94 0)
				(effects
					(font
						(size 1.27 1.27)
					)
					(justify left bottom)
					(hide yes)
				)
			)
			(property "Dielectric" "C0G"
				(at 20.32 -30.48 0)
				(effects
					(font
						(size 1.27 1.27)
					)
					(justify left bottom)
					(hide yes)
				)
			)
			(symbol "C_47p_0402_0_1"
				(polyline
					(pts
						(xy 2.032 -1.524) (xy 2.032 1.524)
					)
					(stroke
						(width 0.3048)
						(type default)
					)
					(fill
						(type none)
					)
				)
				(polyline
					(pts
						(xy 3.048 -1.524) (xy 3.048 1.524)
					)
					(stroke
						(width 0.3302)
						(type default)
					)
					(fill
						(type none)
					)
				)
			)
			(symbol "C_47p_0402_1_1"
				(pin passive line
					(at 0 0 0)
					(length 2.032)
					(name "~"
						(effects
							(font
								(size 1.27 1.27)
							)
						)
					)
					(number "1"
						(effects
							(font
								(size 1.27 1.27)
							)
						)
					)
				)
				(pin passive line
					(at 5.08 0 180)
					(length 2.032)
					(name "~"
						(effects
							(font
								(size 1.27 1.27)
							)
						)
					)
					(number "2"
						(effects
							(font
								(size 1.27 1.27)
							)
						)
					)
				)
			)
		)
	(symbol "antmicroCapacitors0402:C_4n7_0402"
			(pin_numbers
				(hide yes)
			)
			(pin_names
				(hide yes)
			)
			(exclude_from_sim no)
			(in_bom yes)
			(on_board yes)
			(property "Reference" "C"
				(at 20.32 -5.08 0)
				(effects
					(font
						(size 1.27 1.27)
						(thickness 0.15)
					)
					(justify left bottom)
				)
			)
			(property "Value" "C_4n7_0402"
				(at 20.32 -10.16 0)
				(effects
					(font
						(size 1.27 1.27)
						(thickness 0.15)
					)
					(justify left bottom)
					(hide yes)
				)
			)
			(property "Footprint" "antmicro-footprints:C_0402_1005Metric"
				(at 20.32 -12.7 0)
				(effects
					(font
						(size 1.27 1.27)
						(thickness 0.15)
					)
					(justify left bottom)
					(hide yes)
				)
			)
			(property "Datasheet" ""
				(at 20.32 -15.24 0)
				(effects
					(font
						(size 1.27 1.27)
						(thickness 0.15)
					)
					(justify left bottom)
					(hide yes)
				)
			)
			(property "Description" ""
				(at 0 0 0)
				(effects
					(font
						(size 1.27 1.27)
					)
					(hide yes)
				)
			)
			(property "MPN" "CGA2B3X7S2A472K050BB"
				(at 20.32 -17.78 0)
				(effects
					(font
						(size 1.27 1.27)
						(thickness 0.15)
					)
					(justify left bottom)
					(hide yes)
				)
			)
			(property "Manufacturer" "TDK"
				(at 20.32 -20.32 0)
				(effects
					(font
						(size 1.27 1.27)
						(thickness 0.15)
					)
					(justify left bottom)
					(hide yes)
				)
			)
			(property "License" "Apache-2.0"
				(at 20.32 -22.86 0)
				(effects
					(font
						(size 1.27 1.27)
						(thickness 0.15)
					)
					(justify left bottom)
					(hide yes)
				)
			)
			(property "Author" "Antmicro"
				(at 20.32 -25.4 0)
				(effects
					(font
						(size 1.27 1.27)
						(thickness 0.15)
					)
					(justify left bottom)
					(hide yes)
				)
			)
			(property "Val" "4n7"
				(at 20.32 -7.62 0)
				(effects
					(font
						(size 1.27 1.27)
						(thickness 0.15)
					)
					(justify left bottom)
				)
			)
			(property "Voltage" ""
				(at 20.32 -27.94 0)
				(effects
					(font
						(size 1.27 1.27)
					)
					(justify left bottom)
					(hide yes)
				)
			)
			(property "Dielectric" ""
				(at 20.32 -30.48 0)
				(effects
					(font
						(size 1.27 1.27)
					)
					(justify left bottom)
					(hide yes)
				)
			)
			(symbol "C_4n7_0402_0_1"
				(polyline
					(pts
						(xy 2.032 -1.524) (xy 2.032 1.524)
					)
					(stroke
						(width 0.3048)
						(type default)
					)
					(fill
						(type none)
					)
				)
				(polyline
					(pts
						(xy 3.048 -1.524) (xy 3.048 1.524)
					)
					(stroke
						(width 0.3302)
						(type default)
					)
					(fill
						(type none)
					)
				)
			)
			(symbol "C_4n7_0402_1_1"
				(pin passive line
					(at 0 0 0)
					(length 2.032)
					(name "~"
						(effects
							(font
								(size 1.27 1.27)
							)
						)
					)
					(number "1"
						(effects
							(font
								(size 1.27 1.27)
							)
						)
					)
				)
				(pin passive line
					(at 5.08 0 180)
					(length 2.032)
					(name "~"
						(effects
							(font
								(size 1.27 1.27)
							)
						)
					)
					(number "2"
						(effects
							(font
								(size 1.27 1.27)
							)
						)
					)
				)
			)
		)
	(symbol "antmicroCapacitors0402:C_4u7_0402"
			(pin_numbers
				(hide yes)
			)
			(pin_names
				(hide yes)
			)
			(exclude_from_sim no)
			(in_bom yes)
			(on_board yes)
			(property "Reference" "C"
				(at 20.32 -5.08 0)
				(effects
					(font
						(size 1.27 1.27)
						(thickness 0.15)
					)
					(justify left bottom)
				)
			)
			(property "Value" "C_4u7_0402"
				(at 20.32 -10.16 0)
				(effects
					(font
						(size 1.27 1.27)
						(thickness 0.15)
					)
					(justify left bottom)
					(hide yes)
				)
			)
			(property "Footprint" "antmicro-footprints:C_0402_1005Metric"
				(at 20.32 -12.7 0)
				(effects
					(font
						(size 1.27 1.27)
						(thickness 0.15)
					)
					(justify left bottom)
					(hide yes)
				)
			)
			(property "Datasheet" ""
				(at 20.32 -15.24 0)
				(effects
					(font
						(size 1.27 1.27)
						(thickness 0.15)
					)
					(justify left bottom)
					(hide yes)
				)
			)
			(property "Description" ""
				(at 0 0 0)
				(effects
					(font
						(size 1.27 1.27)
					)
					(hide yes)
				)
			)
			(property "MPN" "GRM155R61A475MEAAD"
				(at 20.32 -17.78 0)
				(effects
					(font
						(size 1.27 1.27)
						(thickness 0.15)
					)
					(justify left bottom)
					(hide yes)
				)
			)
			(property "Manufacturer" "Murata"
				(at 20.32 -20.32 0)
				(effects
					(font
						(size 1.27 1.27)
						(thickness 0.15)
					)
					(justify left bottom)
					(hide yes)
				)
			)
			(property "License" "Apache-2.0"
				(at 20.32 -22.86 0)
				(effects
					(font
						(size 1.27 1.27)
						(thickness 0.15)
					)
					(justify left bottom)
					(hide yes)
				)
			)
			(property "Author" "Antmicro"
				(at 20.32 -25.4 0)
				(effects
					(font
						(size 1.27 1.27)
						(thickness 0.15)
					)
					(justify left bottom)
					(hide yes)
				)
			)
			(property "Val" "4u7"
				(at 20.32 -7.62 0)
				(effects
					(font
						(size 1.27 1.27)
						(thickness 0.15)
					)
					(justify left bottom)
				)
			)
			(property "Voltage" ""
				(at 20.32 -27.94 0)
				(effects
					(font
						(size 1.27 1.27)
					)
					(justify left bottom)
					(hide yes)
				)
			)
			(property "Dielectric" ""
				(at 20.32 -30.48 0)
				(effects
					(font
						(size 1.27 1.27)
					)
					(justify left bottom)
					(hide yes)
				)
			)
			(symbol "C_4u7_0402_0_1"
				(polyline
					(pts
						(xy 2.032 -1.524) (xy 2.032 1.524)
					)
					(stroke
						(width 0.3048)
						(type default)
					)
					(fill
						(type none)
					)
				)
				(polyline
					(pts
						(xy 3.048 -1.524) (xy 3.048 1.524)
					)
					(stroke
						(width 0.3302)
						(type default)
					)
					(fill
						(type none)
					)
				)
			)
			(symbol "C_4u7_0402_1_1"
				(pin passive line
					(at 0 0 0)
					(length 2.032)
					(name "~"
						(effects
							(font
								(size 1.27 1.27)
							)
						)
					)
					(number "1"
						(effects
							(font
								(size 1.27 1.27)
							)
						)
					)
				)
				(pin passive line
					(at 5.08 0 180)
					(length 2.032)
					(name "~"
						(effects
							(font
								(size 1.27 1.27)
							)
						)
					)
					(number "2"
						(effects
							(font
								(size 1.27 1.27)
							)
						)
					)
				)
			)
		)
	(symbol "antmicroCapacitors0603:C_100n_0603"
			(pin_numbers
				(hide yes)
			)
			(pin_names
				(hide yes)
			)
			(exclude_from_sim no)
			(in_bom yes)
			(on_board yes)
			(property "Reference" "C"
				(at 20.32 -5.08 0)
				(effects
					(font
						(size 1.27 1.27)
						(thickness 0.15)
					)
					(justify left bottom)
				)
			)
			(property "Value" "C_100n_0603"
				(at 20.32 -10.16 0)
				(effects
					(font
						(size 1.27 1.27)
						(thickness 0.15)
					)
					(justify left bottom)
					(hide yes)
				)
			)
			(property "Footprint" "antmicro-footprints:C_0603_1608Metric"
				(at 20.32 -12.7 0)
				(effects
					(font
						(size 1.27 1.27)
						(thickness 0.15)
					)
					(justify left bottom)
					(hide yes)
				)
			)
			(property "Datasheet" ""
				(at 20.32 -15.24 0)
				(effects
					(font
						(size 1.27 1.27)
						(thickness 0.15)
					)
					(justify left bottom)
					(hide yes)
				)
			)
			(property "Description" ""
				(at 0 0 0)
				(effects
					(font
						(size 1.27 1.27)
					)
					(hide yes)
				)
			)
			(property "MPN" "0603YC104KAZ2A"
				(at 20.32 -17.78 0)
				(effects
					(font
						(size 1.27 1.27)
						(thickness 0.15)
					)
					(justify left bottom)
					(hide yes)
				)
			)
			(property "Manufacturer" "AVX"
				(at 20.32 -20.32 0)
				(effects
					(font
						(size 1.27 1.27)
						(thickness 0.15)
					)
					(justify left bottom)
					(hide yes)
				)
			)
			(property "License" "Apache-2.0"
				(at 20.32 -22.86 0)
				(effects
					(font
						(size 1.27 1.27)
						(thickness 0.15)
					)
					(justify left bottom)
					(hide yes)
				)
			)
			(property "Author" "Antmicro"
				(at 20.32 -25.4 0)
				(effects
					(font
						(size 1.27 1.27)
						(thickness 0.15)
					)
					(justify left bottom)
					(hide yes)
				)
			)
			(property "Val" "100n"
				(at 20.32 -7.62 0)
				(effects
					(font
						(size 1.27 1.27)
						(thickness 0.15)
					)
					(justify left bottom)
				)
			)
			(property "Voltage" ""
				(at 20.32 -27.94 0)
				(effects
					(font
						(size 1.27 1.27)
					)
					(justify left bottom)
					(hide yes)
				)
			)
			(property "Dielectric" ""
				(at 20.32 -30.48 0)
				(effects
					(font
						(size 1.27 1.27)
					)
					(justify left bottom)
					(hide yes)
				)
			)
			(symbol "C_100n_0603_0_1"
				(polyline
					(pts
						(xy 2.032 -1.524) (xy 2.032 1.524)
					)
					(stroke
						(width 0.3048)
						(type default)
					)
					(fill
						(type none)
					)
				)
				(polyline
					(pts
						(xy 3.048 -1.524) (xy 3.048 1.524)
					)
					(stroke
						(width 0.3302)
						(type default)
					)
					(fill
						(type none)
					)
				)
			)
			(symbol "C_100n_0603_1_1"
				(pin passive line
					(at 0 0 0)
					(length 2.032)
					(name "~"
						(effects
							(font
								(size 1.27 1.27)
							)
						)
					)
					(number "1"
						(effects
							(font
								(size 1.27 1.27)
							)
						)
					)
				)
				(pin passive line
					(at 5.08 0 180)
					(length 2.032)
					(name "~"
						(effects
							(font
								(size 1.27 1.27)
							)
						)
					)
					(number "2"
						(effects
							(font
								(size 1.27 1.27)
							)
						)
					)
				)
			)
		)
	(symbol "antmicroCapacitors0603:C_10n_0603"
			(pin_numbers
				(hide yes)
			)
			(pin_names
				(hide yes)
			)
			(exclude_from_sim no)
			(in_bom yes)
			(on_board yes)
			(property "Reference" "C"
				(at 20.32 -5.08 0)
				(effects
					(font
						(size 1.27 1.27)
						(thickness 0.15)
					)
					(justify left bottom)
				)
			)
			(property "Value" "C_10n_0603"
				(at 20.32 -10.16 0)
				(effects
					(font
						(size 1.27 1.27)
						(thickness 0.15)
					)
					(justify left bottom)
					(hide yes)
				)
			)
			(property "Footprint" "antmicro-footprints:C_0603_1608Metric"
				(at 20.32 -12.7 0)
				(effects
					(font
						(size 1.27 1.27)
						(thickness 0.15)
					)
					(justify left bottom)
					(hide yes)
				)
			)
			(property "Datasheet" ""
				(at 20.32 -15.24 0)
				(effects
					(font
						(size 1.27 1.27)
						(thickness 0.15)
					)
					(justify left bottom)
					(hide yes)
				)
			)
			(property "Description" ""
				(at 0 0 0)
				(effects
					(font
						(size 1.27 1.27)
					)
					(hide yes)
				)
			)
			(property "MPN" "06031C103JAT2A"
				(at 20.32 -17.78 0)
				(effects
					(font
						(size 1.27 1.27)
						(thickness 0.15)
					)
					(justify left bottom)
					(hide yes)
				)
			)
			(property "Manufacturer" "AVX"
				(at 20.32 -20.32 0)
				(effects
					(font
						(size 1.27 1.27)
						(thickness 0.15)
					)
					(justify left bottom)
					(hide yes)
				)
			)
			(property "License" "Apache-2.0"
				(at 20.32 -22.86 0)
				(effects
					(font
						(size 1.27 1.27)
						(thickness 0.15)
					)
					(justify left bottom)
					(hide yes)
				)
			)
			(property "Author" "Antmicro"
				(at 20.32 -25.4 0)
				(effects
					(font
						(size 1.27 1.27)
						(thickness 0.15)
					)
					(justify left bottom)
					(hide yes)
				)
			)
			(property "Val" "10n"
				(at 20.32 -7.62 0)
				(effects
					(font
						(size 1.27 1.27)
						(thickness 0.15)
					)
					(justify left bottom)
				)
			)
			(property "Voltage" ""
				(at 20.32 -27.94 0)
				(effects
					(font
						(size 1.27 1.27)
					)
					(justify left bottom)
					(hide yes)
				)
			)
			(property "Dielectric" ""
				(at 20.32 -30.48 0)
				(effects
					(font
						(size 1.27 1.27)
					)
					(justify left bottom)
					(hide yes)
				)
			)
			(symbol "C_10n_0603_0_1"
				(polyline
					(pts
						(xy 2.032 -1.524) (xy 2.032 1.524)
					)
					(stroke
						(width 0.3048)
						(type default)
					)
					(fill
						(type none)
					)
				)
				(polyline
					(pts
						(xy 3.048 -1.524) (xy 3.048 1.524)
					)
					(stroke
						(width 0.3302)
						(type default)
					)
					(fill
						(type none)
					)
				)
			)
			(symbol "C_10n_0603_1_1"
				(pin passive line
					(at 0 0 0)
					(length 2.032)
					(name "~"
						(effects
							(font
								(size 1.27 1.27)
							)
						)
					)
					(number "1"
						(effects
							(font
								(size 1.27 1.27)
							)
						)
					)
				)
				(pin passive line
					(at 5.08 0 180)
					(length 2.032)
					(name "~"
						(effects
							(font
								(size 1.27 1.27)
							)
						)
					)
					(number "2"
						(effects
							(font
								(size 1.27 1.27)
							)
						)
					)
				)
			)
		)
	(symbol "antmicroCapacitors0603:C_10u_0603"
			(pin_numbers
				(hide yes)
			)
			(pin_names
				(hide yes)
			)
			(exclude_from_sim no)
			(in_bom yes)
			(on_board yes)
			(property "Reference" "C"
				(at 20.32 -5.08 0)
				(effects
					(font
						(size 1.27 1.27)
						(thickness 0.15)
					)
					(justify left bottom)
				)
			)
			(property "Value" "C_10u_0603"
				(at 20.32 -10.16 0)
				(effects
					(font
						(size 1.27 1.27)
						(thickness 0.15)
					)
					(justify left bottom)
					(hide yes)
				)
			)
			(property "Footprint" "antmicro-footprints:C_0603_1608Metric"
				(at 20.32 -12.7 0)
				(effects
					(font
						(size 1.27 1.27)
						(thickness 0.15)
					)
					(justify left bottom)
					(hide yes)
				)
			)
			(property "Datasheet" ""
				(at 20.32 -15.24 0)
				(effects
					(font
						(size 1.27 1.27)
						(thickness 0.15)
					)
					(justify left bottom)
					(hide yes)
				)
			)
			(property "Description" ""
				(at 0 0 0)
				(effects
					(font
						(size 1.27 1.27)
					)
					(hide yes)
				)
			)
			(property "MPN" "GRM188R61A106KE69D"
				(at 20.32 -17.78 0)
				(effects
					(font
						(size 1.27 1.27)
						(thickness 0.15)
					)
					(justify left bottom)
					(hide yes)
				)
			)
			(property "Manufacturer" "Murata"
				(at 20.32 -20.32 0)
				(effects
					(font
						(size 1.27 1.27)
						(thickness 0.15)
					)
					(justify left bottom)
					(hide yes)
				)
			)
			(property "License" "Apache-2.0"
				(at 20.32 -22.86 0)
				(effects
					(font
						(size 1.27 1.27)
						(thickness 0.15)
					)
					(justify left bottom)
					(hide yes)
				)
			)
			(property "Author" "Antmicro"
				(at 20.32 -25.4 0)
				(effects
					(font
						(size 1.27 1.27)
						(thickness 0.15)
					)
					(justify left bottom)
					(hide yes)
				)
			)
			(property "Val" "10u"
				(at 20.32 -7.62 0)
				(effects
					(font
						(size 1.27 1.27)
						(thickness 0.15)
					)
					(justify left bottom)
				)
			)
			(property "Voltage" ""
				(at 20.32 -27.94 0)
				(effects
					(font
						(size 1.27 1.27)
					)
					(justify left bottom)
					(hide yes)
				)
			)
			(property "Dielectric" "template_dielectric"
				(at 20.32 -30.48 0)
				(effects
					(font
						(size 1.27 1.27)
					)
					(justify left bottom)
					(hide yes)
				)
			)
			(symbol "C_10u_0603_0_1"
				(polyline
					(pts
						(xy 2.032 -1.524) (xy 2.032 1.524)
					)
					(stroke
						(width 0.3048)
						(type default)
					)
					(fill
						(type none)
					)
				)
				(polyline
					(pts
						(xy 3.048 -1.524) (xy 3.048 1.524)
					)
					(stroke
						(width 0.3302)
						(type default)
					)
					(fill
						(type none)
					)
				)
			)
			(symbol "C_10u_0603_1_1"
				(pin passive line
					(at 0 0 0)
					(length 2.032)
					(name "~"
						(effects
							(font
								(size 1.27 1.27)
							)
						)
					)
					(number "1"
						(effects
							(font
								(size 1.27 1.27)
							)
						)
					)
				)
				(pin passive line
					(at 5.08 0 180)
					(length 2.032)
					(name "~"
						(effects
							(font
								(size 1.27 1.27)
							)
						)
					)
					(number "2"
						(effects
							(font
								(size 1.27 1.27)
							)
						)
					)
				)
			)
		)
	(symbol "antmicroCapacitors0603:C_10u_25V_0603"
			(pin_numbers
				(hide yes)
			)
			(pin_names
				(hide yes)
			)
			(exclude_from_sim no)
			(in_bom yes)
			(on_board yes)
			(property "Reference" "C"
				(at 20.32 -5.08 0)
				(effects
					(font
						(size 1.27 1.27)
						(thickness 0.15)
					)
					(justify left bottom)
				)
			)
			(property "Value" "C_10u_25V_0603"
				(at 20.32 -10.16 0)
				(effects
					(font
						(size 1.27 1.27)
						(thickness 0.15)
					)
					(justify left bottom)
					(hide yes)
				)
			)
			(property "Footprint" "antmicro-footprints:C_0603_1608Metric"
				(at 20.32 -12.7 0)
				(effects
					(font
						(size 1.27 1.27)
						(thickness 0.15)
					)
					(justify left bottom)
					(hide yes)
				)
			)
			(property "Datasheet" ""
				(at 20.32 -15.24 0)
				(effects
					(font
						(size 1.27 1.27)
						(thickness 0.15)
					)
					(justify left bottom)
					(hide yes)
				)
			)
			(property "Description" ""
				(at 0 0 0)
				(effects
					(font
						(size 1.27 1.27)
					)
					(hide yes)
				)
			)
			(property "MPN" "C1608X5R1E106M080AC"
				(at 20.32 -17.78 0)
				(effects
					(font
						(size 1.27 1.27)
						(thickness 0.15)
					)
					(justify left bottom)
					(hide yes)
				)
			)
			(property "Manufacturer" "TDK"
				(at 20.32 -20.32 0)
				(effects
					(font
						(size 1.27 1.27)
						(thickness 0.15)
					)
					(justify left bottom)
					(hide yes)
				)
			)
			(property "License" "Apache-2.0"
				(at 20.32 -22.86 0)
				(effects
					(font
						(size 1.27 1.27)
						(thickness 0.15)
					)
					(justify left bottom)
					(hide yes)
				)
			)
			(property "Author" "Antmicro"
				(at 20.32 -25.4 0)
				(effects
					(font
						(size 1.27 1.27)
						(thickness 0.15)
					)
					(justify left bottom)
					(hide yes)
				)
			)
			(property "Val" "10u/25V"
				(at 20.32 -7.62 0)
				(effects
					(font
						(size 1.27 1.27)
						(thickness 0.15)
					)
					(justify left bottom)
				)
			)
			(property "Voltage" ""
				(at 20.32 -27.94 0)
				(effects
					(font
						(size 1.27 1.27)
					)
					(justify left bottom)
					(hide yes)
				)
			)
			(property "Dielectric" ""
				(at 20.32 -30.48 0)
				(effects
					(font
						(size 1.27 1.27)
					)
					(justify left bottom)
					(hide yes)
				)
			)
			(symbol "C_10u_25V_0603_0_1"
				(polyline
					(pts
						(xy 2.032 -1.524) (xy 2.032 1.524)
					)
					(stroke
						(width 0.3048)
						(type default)
					)
					(fill
						(type none)
					)
				)
				(polyline
					(pts
						(xy 3.048 -1.524) (xy 3.048 1.524)
					)
					(stroke
						(width 0.3302)
						(type default)
					)
					(fill
						(type none)
					)
				)
			)
			(symbol "C_10u_25V_0603_1_1"
				(pin passive line
					(at 0 0 0)
					(length 2.032)
					(name "~"
						(effects
							(font
								(size 1.27 1.27)
							)
						)
					)
					(number "1"
						(effects
							(font
								(size 1.27 1.27)
							)
						)
					)
				)
				(pin passive line
					(at 5.08 0 180)
					(length 2.032)
					(name "~"
						(effects
							(font
								(size 1.27 1.27)
							)
						)
					)
					(number "2"
						(effects
							(font
								(size 1.27 1.27)
							)
						)
					)
				)
			)
		)
	(symbol "antmicroCapacitors0603:C_1u_0603"
			(pin_numbers
				(hide yes)
			)
			(pin_names
				(hide yes)
			)
			(exclude_from_sim no)
			(in_bom yes)
			(on_board yes)
			(property "Reference" "C"
				(at 20.32 -5.08 0)
				(effects
					(font
						(size 1.27 1.27)
						(thickness 0.15)
					)
					(justify left bottom)
				)
			)
			(property "Value" "C_1u_0603"
				(at 20.32 -10.16 0)
				(effects
					(font
						(size 1.27 1.27)
						(thickness 0.15)
					)
					(justify left bottom)
					(hide yes)
				)
			)
			(property "Footprint" "antmicro-footprints:C_0603_1608Metric"
				(at 20.32 -12.7 0)
				(effects
					(font
						(size 1.27 1.27)
						(thickness 0.15)
					)
					(justify left bottom)
					(hide yes)
				)
			)
			(property "Datasheet" ""
				(at 20.32 -15.24 0)
				(effects
					(font
						(size 1.27 1.27)
						(thickness 0.15)
					)
					(justify left bottom)
					(hide yes)
				)
			)
			(property "Description" ""
				(at 0 0 0)
				(effects
					(font
						(size 1.27 1.27)
					)
					(hide yes)
				)
			)
			(property "MPN" "0603YD105KAT2A"
				(at 20.32 -17.78 0)
				(effects
					(font
						(size 1.27 1.27)
						(thickness 0.15)
					)
					(justify left bottom)
					(hide yes)
				)
			)
			(property "Manufacturer" "Walsin"
				(at 20.32 -20.32 0)
				(effects
					(font
						(size 1.27 1.27)
						(thickness 0.15)
					)
					(justify left bottom)
					(hide yes)
				)
			)
			(property "License" "Apache-2.0"
				(at 20.32 -22.86 0)
				(effects
					(font
						(size 1.27 1.27)
						(thickness 0.15)
					)
					(justify left bottom)
					(hide yes)
				)
			)
			(property "Author" "Antmicro"
				(at 20.32 -25.4 0)
				(effects
					(font
						(size 1.27 1.27)
						(thickness 0.15)
					)
					(justify left bottom)
					(hide yes)
				)
			)
			(property "Val" "1u"
				(at 20.32 -7.62 0)
				(effects
					(font
						(size 1.27 1.27)
						(thickness 0.15)
					)
					(justify left bottom)
				)
			)
			(property "Voltage" ""
				(at 20.32 -27.94 0)
				(effects
					(font
						(size 1.27 1.27)
					)
					(justify left bottom)
					(hide yes)
				)
			)
			(property "Dielectric" ""
				(at 20.32 -30.48 0)
				(effects
					(font
						(size 1.27 1.27)
					)
					(justify left bottom)
					(hide yes)
				)
			)
			(symbol "C_1u_0603_0_1"
				(polyline
					(pts
						(xy 2.032 -1.524) (xy 2.032 1.524)
					)
					(stroke
						(width 0.3048)
						(type default)
					)
					(fill
						(type none)
					)
				)
				(polyline
					(pts
						(xy 3.048 -1.524) (xy 3.048 1.524)
					)
					(stroke
						(width 0.3302)
						(type default)
					)
					(fill
						(type none)
					)
				)
			)
			(symbol "C_1u_0603_1_1"
				(pin passive line
					(at 0 0 0)
					(length 2.032)
					(name "~"
						(effects
							(font
								(size 1.27 1.27)
							)
						)
					)
					(number "1"
						(effects
							(font
								(size 1.27 1.27)
							)
						)
					)
				)
				(pin passive line
					(at 5.08 0 180)
					(length 2.032)
					(name "~"
						(effects
							(font
								(size 1.27 1.27)
							)
						)
					)
					(number "2"
						(effects
							(font
								(size 1.27 1.27)
							)
						)
					)
				)
			)
		)
	(symbol "antmicroCapacitors0603:C_22u_0603"
			(pin_numbers
				(hide yes)
			)
			(pin_names
				(hide yes)
			)
			(exclude_from_sim no)
			(in_bom yes)
			(on_board yes)
			(property "Reference" "C"
				(at 20.32 -5.08 0)
				(effects
					(font
						(size 1.27 1.27)
						(thickness 0.15)
					)
					(justify left bottom)
				)
			)
			(property "Value" "C_22u_0603"
				(at 20.32 -10.16 0)
				(effects
					(font
						(size 1.27 1.27)
						(thickness 0.15)
					)
					(justify left bottom)
					(hide yes)
				)
			)
			(property "Footprint" "antmicro-footprints:C_0603_1608Metric"
				(at 20.32 -12.7 0)
				(effects
					(font
						(size 1.27 1.27)
						(thickness 0.15)
					)
					(justify left bottom)
					(hide yes)
				)
			)
			(property "Datasheet" ""
				(at 20.32 -15.24 0)
				(effects
					(font
						(size 1.27 1.27)
						(thickness 0.15)
					)
					(justify left bottom)
					(hide yes)
				)
			)
			(property "Description" ""
				(at 0 0 0)
				(effects
					(font
						(size 1.27 1.27)
					)
					(hide yes)
				)
			)
			(property "MPN" "GRM188R60J226MEA0D"
				(at 20.32 -17.78 0)
				(effects
					(font
						(size 1.27 1.27)
						(thickness 0.15)
					)
					(justify left bottom)
					(hide yes)
				)
			)
			(property "Manufacturer" "Murata"
				(at 20.32 -20.32 0)
				(effects
					(font
						(size 1.27 1.27)
						(thickness 0.15)
					)
					(justify left bottom)
					(hide yes)
				)
			)
			(property "License" "Apache-2.0"
				(at 20.32 -22.86 0)
				(effects
					(font
						(size 1.27 1.27)
						(thickness 0.15)
					)
					(justify left bottom)
					(hide yes)
				)
			)
			(property "Author" "Antmicro"
				(at 20.32 -25.4 0)
				(effects
					(font
						(size 1.27 1.27)
						(thickness 0.15)
					)
					(justify left bottom)
					(hide yes)
				)
			)
			(property "Val" "22u"
				(at 20.32 -7.62 0)
				(effects
					(font
						(size 1.27 1.27)
						(thickness 0.15)
					)
					(justify left bottom)
				)
			)
			(property "Voltage" ""
				(at 20.32 -27.94 0)
				(effects
					(font
						(size 1.27 1.27)
					)
					(justify left bottom)
					(hide yes)
				)
			)
			(property "Dielectric" ""
				(at 20.32 -30.48 0)
				(effects
					(font
						(size 1.27 1.27)
					)
					(justify left bottom)
					(hide yes)
				)
			)
			(symbol "C_22u_0603_0_1"
				(polyline
					(pts
						(xy 2.032 -1.524) (xy 2.032 1.524)
					)
					(stroke
						(width 0.3048)
						(type default)
					)
					(fill
						(type none)
					)
				)
				(polyline
					(pts
						(xy 3.048 -1.524) (xy 3.048 1.524)
					)
					(stroke
						(width 0.3302)
						(type default)
					)
					(fill
						(type none)
					)
				)
			)
			(symbol "C_22u_0603_1_1"
				(pin passive line
					(at 0 0 0)
					(length 2.032)
					(name "~"
						(effects
							(font
								(size 1.27 1.27)
							)
						)
					)
					(number "1"
						(effects
							(font
								(size 1.27 1.27)
							)
						)
					)
				)
				(pin passive line
					(at 5.08 0 180)
					(length 2.032)
					(name "~"
						(effects
							(font
								(size 1.27 1.27)
							)
						)
					)
					(number "2"
						(effects
							(font
								(size 1.27 1.27)
							)
						)
					)
				)
			)
		)
	(symbol "antmicroCapacitors0603:C_47u_0603"
			(pin_numbers
				(hide yes)
			)
			(pin_names
				(hide yes)
			)
			(exclude_from_sim no)
			(in_bom yes)
			(on_board yes)
			(property "Reference" "C"
				(at 20.32 -5.08 0)
				(effects
					(font
						(size 1.27 1.27)
						(thickness 0.15)
					)
					(justify left bottom)
				)
			)
			(property "Value" "C_47u_0603"
				(at 20.32 -10.16 0)
				(effects
					(font
						(size 1.27 1.27)
						(thickness 0.15)
					)
					(justify left bottom)
					(hide yes)
				)
			)
			(property "Footprint" "antmicro-footprints:C_0603_1608Metric"
				(at 20.32 -12.7 0)
				(effects
					(font
						(size 1.27 1.27)
						(thickness 0.15)
					)
					(justify left bottom)
					(hide yes)
				)
			)
			(property "Datasheet" ""
				(at 20.32 -15.24 0)
				(effects
					(font
						(size 1.27 1.27)
						(thickness 0.15)
					)
					(justify left bottom)
					(hide yes)
				)
			)
			(property "Description" ""
				(at 0 0 0)
				(effects
					(font
						(size 1.27 1.27)
					)
					(hide yes)
				)
			)
			(property "MPN" "GRM188R60J476ME15D"
				(at 20.32 -17.78 0)
				(effects
					(font
						(size 1.27 1.27)
						(thickness 0.15)
					)
					(justify left bottom)
					(hide yes)
				)
			)
			(property "Manufacturer" "Murata"
				(at 20.32 -20.32 0)
				(effects
					(font
						(size 1.27 1.27)
						(thickness 0.15)
					)
					(justify left bottom)
					(hide yes)
				)
			)
			(property "License" "Apache-2.0"
				(at 20.32 -22.86 0)
				(effects
					(font
						(size 1.27 1.27)
						(thickness 0.15)
					)
					(justify left bottom)
					(hide yes)
				)
			)
			(property "Author" "Antmicro"
				(at 20.32 -25.4 0)
				(effects
					(font
						(size 1.27 1.27)
						(thickness 0.15)
					)
					(justify left bottom)
					(hide yes)
				)
			)
			(property "Val" "47u"
				(at 20.32 -7.62 0)
				(effects
					(font
						(size 1.27 1.27)
						(thickness 0.15)
					)
					(justify left bottom)
				)
			)
			(property "Voltage" ""
				(at 20.32 -27.94 0)
				(effects
					(font
						(size 1.27 1.27)
					)
					(justify left bottom)
					(hide yes)
				)
			)
			(property "Dielectric" ""
				(at 20.32 -30.48 0)
				(effects
					(font
						(size 1.27 1.27)
					)
					(justify left bottom)
					(hide yes)
				)
			)
			(symbol "C_47u_0603_0_1"
				(polyline
					(pts
						(xy 2.032 -1.524) (xy 2.032 1.524)
					)
					(stroke
						(width 0.3048)
						(type default)
					)
					(fill
						(type none)
					)
				)
				(polyline
					(pts
						(xy 3.048 -1.524) (xy 3.048 1.524)
					)
					(stroke
						(width 0.3302)
						(type default)
					)
					(fill
						(type none)
					)
				)
			)
			(symbol "C_47u_0603_1_1"
				(pin passive line
					(at 0 0 0)
					(length 2.032)
					(name "~"
						(effects
							(font
								(size 1.27 1.27)
							)
						)
					)
					(number "1"
						(effects
							(font
								(size 1.27 1.27)
							)
						)
					)
				)
				(pin passive line
					(at 5.08 0 180)
					(length 2.032)
					(name "~"
						(effects
							(font
								(size 1.27 1.27)
							)
						)
					)
					(number "2"
						(effects
							(font
								(size 1.27 1.27)
							)
						)
					)
				)
			)
		)
	(symbol "antmicroCapacitorsmisc:C_100n_0201"
			(pin_numbers
				(hide yes)
			)
			(pin_names
				(hide yes)
			)
			(exclude_from_sim no)
			(in_bom yes)
			(on_board yes)
			(property "Reference" "C"
				(at 20.32 -5.08 0)
				(effects
					(font
						(size 1.27 1.27)
						(thickness 0.15)
					)
					(justify left bottom)
				)
			)
			(property "Value" "C_100n_0201"
				(at 20.32 -10.16 0)
				(effects
					(font
						(size 1.27 1.27)
						(thickness 0.15)
					)
					(justify left bottom)
					(hide yes)
				)
			)
			(property "Footprint" "antmicro-footprints:C_0201"
				(at 20.32 -12.7 0)
				(effects
					(font
						(size 1.27 1.27)
						(thickness 0.15)
					)
					(justify left bottom)
					(hide yes)
				)
			)
			(property "Datasheet" ""
				(at 20.32 -15.24 0)
				(effects
					(font
						(size 1.27 1.27)
						(thickness 0.15)
					)
					(justify left bottom)
					(hide yes)
				)
			)
			(property "Description" ""
				(at 0 0 0)
				(effects
					(font
						(size 1.27 1.27)
					)
					(hide yes)
				)
			)
			(property "MPN" "CC0201KRX6S5BB104"
				(at 20.32 -17.78 0)
				(effects
					(font
						(size 1.27 1.27)
						(thickness 0.15)
					)
					(justify left bottom)
					(hide yes)
				)
			)
			(property "Manufacturer" "Yaego"
				(at 20.32 -20.32 0)
				(effects
					(font
						(size 1.27 1.27)
						(thickness 0.15)
					)
					(justify left bottom)
					(hide yes)
				)
			)
			(property "License" "Apache-2.0"
				(at 20.32 -22.86 0)
				(effects
					(font
						(size 1.27 1.27)
						(thickness 0.15)
					)
					(justify left bottom)
					(hide yes)
				)
			)
			(property "Author" "Antmicro"
				(at 20.32 -25.4 0)
				(effects
					(font
						(size 1.27 1.27)
						(thickness 0.15)
					)
					(justify left bottom)
					(hide yes)
				)
			)
			(property "Val" "100n"
				(at 20.32 -7.62 0)
				(effects
					(font
						(size 1.27 1.27)
						(thickness 0.15)
					)
					(justify left bottom)
				)
			)
			(property "Voltage" ""
				(at 20.32 -27.94 0)
				(effects
					(font
						(size 1.27 1.27)
					)
					(justify left bottom)
					(hide yes)
				)
			)
			(property "Dielectric" ""
				(at 20.32 -30.48 0)
				(effects
					(font
						(size 1.27 1.27)
					)
					(justify left bottom)
					(hide yes)
				)
			)
			(symbol "C_100n_0201_0_1"
				(polyline
					(pts
						(xy 2.032 -1.524) (xy 2.032 1.524)
					)
					(stroke
						(width 0.3048)
						(type default)
					)
					(fill
						(type none)
					)
				)
				(polyline
					(pts
						(xy 3.048 -1.524) (xy 3.048 1.524)
					)
					(stroke
						(width 0.3302)
						(type default)
					)
					(fill
						(type none)
					)
				)
			)
			(symbol "C_100n_0201_1_1"
				(pin passive line
					(at 0 0 0)
					(length 2.032)
					(name "~"
						(effects
							(font
								(size 1.27 1.27)
							)
						)
					)
					(number "1"
						(effects
							(font
								(size 1.27 1.27)
							)
						)
					)
				)
				(pin passive line
					(at 5.08 0 180)
					(length 2.032)
					(name "~"
						(effects
							(font
								(size 1.27 1.27)
							)
						)
					)
					(number "2"
						(effects
							(font
								(size 1.27 1.27)
							)
						)
					)
				)
			)
		)
	(symbol "antmicroCapacitorsmisc:C_100n_6V3_0402"
			(pin_numbers
				(hide yes)
			)
			(pin_names
				(hide yes)
			)
			(exclude_from_sim no)
			(in_bom yes)
			(on_board yes)
			(property "Reference" "C"
				(at 20.32 -5.08 0)
				(effects
					(font
						(size 1.27 1.27)
						(thickness 0.15)
					)
					(justify left bottom)
				)
			)
			(property "Value" "C_100n_6V3_0402"
				(at 20.32 -10.16 0)
				(effects
					(font
						(size 1.27 1.27)
						(thickness 0.15)
					)
					(justify left bottom)
					(hide yes)
				)
			)
			(property "Footprint" "antmicro-footprints:C_0402_1005Metric"
				(at 20.32 -12.7 0)
				(effects
					(font
						(size 1.27 1.27)
						(thickness 0.15)
					)
					(justify left bottom)
					(hide yes)
				)
			)
			(property "Datasheet" ""
				(at 20.32 -15.24 0)
				(effects
					(font
						(size 1.27 1.27)
						(thickness 0.15)
					)
					(justify left bottom)
					(hide yes)
				)
			)
			(property "Description" ""
				(at 0 0 0)
				(effects
					(font
						(size 1.27 1.27)
					)
					(hide yes)
				)
			)
			(property "MPN" "0402X104K6R3CT"
				(at 20.32 -17.78 0)
				(effects
					(font
						(size 1.27 1.27)
						(thickness 0.15)
					)
					(justify left bottom)
					(hide yes)
				)
			)
			(property "Manufacturer" "Walsin"
				(at 20.32 -20.32 0)
				(effects
					(font
						(size 1.27 1.27)
						(thickness 0.15)
					)
					(justify left bottom)
					(hide yes)
				)
			)
			(property "License" "Apache-2.0"
				(at 20.32 -22.86 0)
				(effects
					(font
						(size 1.27 1.27)
						(thickness 0.15)
					)
					(justify left bottom)
					(hide yes)
				)
			)
			(property "Author" "Antmicro"
				(at 20.32 -25.4 0)
				(effects
					(font
						(size 1.27 1.27)
						(thickness 0.15)
					)
					(justify left bottom)
					(hide yes)
				)
			)
			(property "Val" "100n"
				(at 20.32 -7.62 0)
				(effects
					(font
						(size 1.27 1.27)
						(thickness 0.15)
					)
					(justify left bottom)
				)
			)
			(property "Voltage" ""
				(at 20.32 -27.94 0)
				(effects
					(font
						(size 1.27 1.27)
					)
					(justify left bottom)
					(hide yes)
				)
			)
			(property "Dielectric" ""
				(at 20.32 -30.48 0)
				(effects
					(font
						(size 1.27 1.27)
					)
					(justify left bottom)
					(hide yes)
				)
			)
			(symbol "C_100n_6V3_0402_0_1"
				(polyline
					(pts
						(xy 2.032 -1.524) (xy 2.032 1.524)
					)
					(stroke
						(width 0.3048)
						(type default)
					)
					(fill
						(type none)
					)
				)
				(polyline
					(pts
						(xy 3.048 -1.524) (xy 3.048 1.524)
					)
					(stroke
						(width 0.3302)
						(type default)
					)
					(fill
						(type none)
					)
				)
			)
			(symbol "C_100n_6V3_0402_1_1"
				(pin passive line
					(at 0 0 0)
					(length 2.032)
					(name "~"
						(effects
							(font
								(size 1.27 1.27)
							)
						)
					)
					(number "1"
						(effects
							(font
								(size 1.27 1.27)
							)
						)
					)
				)
				(pin passive line
					(at 5.08 0 180)
					(length 2.032)
					(name "~"
						(effects
							(font
								(size 1.27 1.27)
							)
						)
					)
					(number "2"
						(effects
							(font
								(size 1.27 1.27)
							)
						)
					)
				)
			)
		)
	(symbol "antmicroCapacitorsmisc:C_22u_0805_16V"
			(pin_numbers
				(hide yes)
			)
			(pin_names
				(hide yes)
			)
			(exclude_from_sim no)
			(in_bom yes)
			(on_board yes)
			(property "Reference" "C"
				(at 20.32 -5.08 0)
				(effects
					(font
						(size 1.27 1.27)
						(thickness 0.15)
					)
					(justify left bottom)
				)
			)
			(property "Value" "C_22u_0805_16V"
				(at 20.32 -10.16 0)
				(effects
					(font
						(size 1.27 1.27)
						(thickness 0.15)
					)
					(justify left bottom)
					(hide yes)
				)
			)
			(property "Footprint" "antmicro-footprints:C_0805_2012Metric"
				(at 20.32 -12.7 0)
				(effects
					(font
						(size 1.27 1.27)
						(thickness 0.15)
					)
					(justify left bottom)
					(hide yes)
				)
			)
			(property "Datasheet" ""
				(at 20.32 -15.24 0)
				(effects
					(font
						(size 1.27 1.27)
						(thickness 0.15)
					)
					(justify left bottom)
					(hide yes)
				)
			)
			(property "Description" ""
				(at 0 0 0)
				(effects
					(font
						(size 1.27 1.27)
					)
					(hide yes)
				)
			)
			(property "MPN" "GRT21BR61C226ME13L"
				(at 20.32 -17.78 0)
				(effects
					(font
						(size 1.27 1.27)
						(thickness 0.15)
					)
					(justify left bottom)
					(hide yes)
				)
			)
			(property "Manufacturer" "Murata"
				(at 20.32 -20.32 0)
				(effects
					(font
						(size 1.27 1.27)
						(thickness 0.15)
					)
					(justify left bottom)
					(hide yes)
				)
			)
			(property "License" "Apache-2.0"
				(at 20.32 -22.86 0)
				(effects
					(font
						(size 1.27 1.27)
						(thickness 0.15)
					)
					(justify left bottom)
					(hide yes)
				)
			)
			(property "Author" "Antmicro"
				(at 20.32 -25.4 0)
				(effects
					(font
						(size 1.27 1.27)
						(thickness 0.15)
					)
					(justify left bottom)
					(hide yes)
				)
			)
			(property "Val" "22u/16V"
				(at 20.32 -7.62 0)
				(effects
					(font
						(size 1.27 1.27)
						(thickness 0.15)
					)
					(justify left bottom)
				)
			)
			(property "Voltage" ""
				(at 20.32 -27.94 0)
				(effects
					(font
						(size 1.27 1.27)
					)
					(justify left bottom)
					(hide yes)
				)
			)
			(property "Dielectric" ""
				(at 20.32 -30.48 0)
				(effects
					(font
						(size 1.27 1.27)
					)
					(justify left bottom)
					(hide yes)
				)
			)
			(symbol "C_22u_0805_16V_0_1"
				(polyline
					(pts
						(xy 2.032 -1.524) (xy 2.032 1.524)
					)
					(stroke
						(width 0.3048)
						(type default)
					)
					(fill
						(type none)
					)
				)
				(polyline
					(pts
						(xy 3.048 -1.524) (xy 3.048 1.524)
					)
					(stroke
						(width 0.3302)
						(type default)
					)
					(fill
						(type none)
					)
				)
			)
			(symbol "C_22u_0805_16V_1_1"
				(pin passive line
					(at 0 0 0)
					(length 2.032)
					(name "~"
						(effects
							(font
								(size 1.27 1.27)
							)
						)
					)
					(number "1"
						(effects
							(font
								(size 1.27 1.27)
							)
						)
					)
				)
				(pin passive line
					(at 5.08 0 180)
					(length 2.032)
					(name "~"
						(effects
							(font
								(size 1.27 1.27)
							)
						)
					)
					(number "2"
						(effects
							(font
								(size 1.27 1.27)
							)
						)
					)
				)
			)
		)
	(symbol "antmicroCapacitorspol:C_Pol_100u_6V_KEMET-T490-A"
			(pin_numbers
				(hide yes)
			)
			(pin_names
				(hide yes)
			)
			(exclude_from_sim no)
			(in_bom yes)
			(on_board yes)
			(property "Reference" "C"
				(at 13.97 0 0)
				(effects
					(font
						(size 1.27 1.27)
						(thickness 0.15)
					)
					(justify left bottom)
				)
			)
			(property "Value" "C_Pol_100u_6V_KEMET-T490-A"
				(at 13.97 -2.54 0)
				(effects
					(font
						(size 1.27 1.27)
						(thickness 0.15)
					)
					(justify left bottom)
					(hide yes)
				)
			)
			(property "Footprint" "antmicro-footprints:C_Pol_EIA-A"
				(at 13.97 -7.62 0)
				(effects
					(font
						(size 1.27 1.27)
						(thickness 0.15)
					)
					(justify left bottom)
					(hide yes)
				)
			)
			(property "Datasheet" "https://www.kemet.com/en/us/capacitors/product/T490A107M006ATE800.html"
				(at 13.97 -10.16 0)
				(effects
					(font
						(size 1.27 1.27)
						(thickness 0.15)
					)
					(justify left bottom)
					(hide yes)
				)
			)
			(property "Description" "Surface Mount Tantalum Capacitor,  Solid SMD 6V 100uF 1206 20% ESR=800mOhms"
				(at 13.97 -25.4 0)
				(effects
					(font
						(size 1.27 1.27)
					)
					(justify left bottom)
					(hide yes)
				)
			)
			(property "Val" "100u"
				(at 13.97 -5.08 0)
				(effects
					(font
						(size 1.27 1.27)
						(thickness 0.15)
					)
					(justify left bottom)
				)
			)
			(property "MPN" "T490A107M006ATE800"
				(at 13.97 -12.7 0)
				(effects
					(font
						(size 1.27 1.27)
						(thickness 0.15)
					)
					(justify left bottom)
					(hide yes)
				)
			)
			(property "Manufacturer" "KEMET"
				(at 13.97 -15.24 0)
				(effects
					(font
						(size 1.27 1.27)
						(thickness 0.15)
					)
					(justify left bottom)
					(hide yes)
				)
			)
			(property "License" "Apache-2.0"
				(at 13.97 -17.78 0)
				(effects
					(font
						(size 1.27 1.27)
						(thickness 0.15)
					)
					(justify left bottom)
					(hide yes)
				)
			)
			(property "Author" "Antmicro"
				(at 13.97 -20.32 0)
				(effects
					(font
						(size 1.27 1.27)
						(thickness 0.15)
					)
					(justify left bottom)
					(hide yes)
				)
			)
			(property "Voltage" "6V"
				(at 13.97 -22.86 0)
				(effects
					(font
						(size 1.27 1.27)
					)
					(justify left bottom)
					(hide yes)
				)
			)
			(property "Dielectric" "template_dielectric"
				(at 13.97 -25.4 0)
				(effects
					(font
						(size 1.27 1.27)
					)
					(justify left bottom)
					(hide yes)
				)
			)
			(property "ki_keywords" "SMT, CAPACITOR, PASSIVE, POLARIZED, TANTALUM"
				(at 0 0 0)
				(effects
					(font
						(size 1.27 1.27)
					)
					(hide yes)
				)
			)
			(symbol "C_Pol_100u_6V_KEMET-T490-A_0_1"
				(polyline
					(pts
						(xy 0.9652 1.27) (xy 0.9652 1.778)
					)
					(stroke
						(width 0)
						(type default)
					)
					(fill
						(type none)
					)
				)
				(polyline
					(pts
						(xy 1.2192 1.524) (xy 0.7112 1.524)
					)
					(stroke
						(width 0)
						(type default)
					)
					(fill
						(type none)
					)
				)
				(rectangle
					(start 1.905 -1.524)
					(end 2.286 1.524)
					(stroke
						(width 0)
						(type default)
					)
					(fill
						(type none)
					)
				)
				(rectangle
					(start 2.921 -1.524)
					(end 3.302 1.524)
					(stroke
						(width 0)
						(type default)
					)
					(fill
						(type outline)
					)
				)
			)
			(symbol "C_Pol_100u_6V_KEMET-T490-A_1_1"
				(pin passive line
					(at 0 0 0)
					(length 1.8542)
					(name "~"
						(effects
							(font
								(size 1.27 1.27)
							)
						)
					)
					(number "1"
						(effects
							(font
								(size 1.27 1.27)
							)
						)
					)
				)
				(pin passive line
					(at 5.08 0 180)
					(length 1.8542)
					(name "~"
						(effects
							(font
								(size 1.27 1.27)
							)
						)
					)
					(number "2"
						(effects
							(font
								(size 1.27 1.27)
							)
						)
					)
				)
			)
		)
	(symbol "antmicroCapacitorspol:C_Pol_330u_6.3V_KEMET-T520-D"
			(pin_numbers
				(hide yes)
			)
			(pin_names
				(hide yes)
			)
			(exclude_from_sim no)
			(in_bom yes)
			(on_board yes)
			(property "Reference" "C"
				(at 13.97 0 0)
				(effects
					(font
						(size 1.27 1.27)
						(thickness 0.15)
					)
					(justify left bottom)
				)
			)
			(property "Value" "C_330u_KEMET_D"
				(at 13.97 -5.08 0)
				(effects
					(font
						(size 1.27 1.27)
						(thickness 0.15)
					)
					(justify left bottom)
					(hide yes)
				)
			)
			(property "Footprint" "antmicro-footprints:C_Pol_EIA-D"
				(at 13.97 -7.62 0)
				(effects
					(font
						(size 1.27 1.27)
						(thickness 0.15)
					)
					(justify left bottom)
					(hide yes)
				)
			)
			(property "Datasheet" ""
				(at 13.97 -10.16 0)
				(effects
					(font
						(size 1.27 1.27)
						(thickness 0.15)
					)
					(justify left bottom)
					(hide yes)
				)
			)
			(property "Description" ""
				(at 0 0 0)
				(effects
					(font
						(size 1.27 1.27)
					)
					(hide yes)
				)
			)
			(property "MPN" "T520D337M006ATE045"
				(at 13.97 -12.7 0)
				(effects
					(font
						(size 1.27 1.27)
						(thickness 0.15)
					)
					(justify left bottom)
					(hide yes)
				)
			)
			(property "Manufacturer" "KEMET"
				(at 13.97 -15.24 0)
				(effects
					(font
						(size 1.27 1.27)
						(thickness 0.15)
					)
					(justify left bottom)
					(hide yes)
				)
			)
			(property "License" "Apache-2.0"
				(at 13.97 -17.78 0)
				(effects
					(font
						(size 1.27 1.27)
						(thickness 0.15)
					)
					(justify left bottom)
					(hide yes)
				)
			)
			(property "Author" "Antmicro"
				(at 13.97 -20.32 0)
				(effects
					(font
						(size 1.27 1.27)
						(thickness 0.15)
					)
					(justify left bottom)
					(hide yes)
				)
			)
			(property "Val" "330u"
				(at 13.97 -2.54 0)
				(effects
					(font
						(size 1.27 1.27)
						(thickness 0.15)
					)
					(justify left bottom)
				)
			)
			(property "Voltage" ""
				(at 13.97 -22.86 0)
				(effects
					(font
						(size 1.27 1.27)
					)
					(justify left bottom)
					(hide yes)
				)
			)
			(property "Dielectric" ""
				(at 13.97 -25.4 0)
				(effects
					(font
						(size 1.27 1.27)
					)
					(justify left bottom)
					(hide yes)
				)
			)
			(symbol "C_Pol_330u_6.3V_KEMET-T520-D_0_1"
				(rectangle
					(start -1.524 -1.905)
					(end 1.524 -2.286)
					(stroke
						(width 0)
						(type default)
					)
					(fill
						(type none)
					)
				)
				(rectangle
					(start -1.524 -2.921)
					(end 1.524 -3.302)
					(stroke
						(width 0)
						(type default)
					)
					(fill
						(type outline)
					)
				)
				(polyline
					(pts
						(xy -1.27 -0.9652) (xy -0.762 -0.9652)
					)
					(stroke
						(width 0)
						(type default)
					)
					(fill
						(type none)
					)
				)
				(polyline
					(pts
						(xy -1.016 -1.2192) (xy -1.016 -0.7112)
					)
					(stroke
						(width 0)
						(type default)
					)
					(fill
						(type none)
					)
				)
			)
			(symbol "C_Pol_330u_6.3V_KEMET-T520-D_1_1"
				(pin passive line
					(at 0 0 270)
					(length 1.8542)
					(name "~"
						(effects
							(font
								(size 1.27 1.27)
							)
						)
					)
					(number "1"
						(effects
							(font
								(size 1.27 1.27)
							)
						)
					)
				)
				(pin passive line
					(at 0 -5.08 90)
					(length 1.8542)
					(name "~"
						(effects
							(font
								(size 1.27 1.27)
							)
						)
					)
					(number "2"
						(effects
							(font
								(size 1.27 1.27)
							)
						)
					)
				)
			)
		)
	(symbol "antmicroDCDCConverters:AP62600SJ-7"
			(exclude_from_sim no)
			(in_bom yes)
			(on_board yes)
			(property "Reference" "U"
				(at 35.56 -2.54 0)
				(effects
					(font
						(size 1.27 1.27)
						(thickness 0.15)
					)
					(justify left bottom)
				)
			)
			(property "Value" "AP62600SJ-7"
				(at 35.56 -7.62 0)
				(effects
					(font
						(size 1.27 1.27)
						(thickness 0.15)
					)
					(justify left bottom)
					(hide yes)
				)
			)
			(property "Footprint" "antmicro-footprints:V-QFN2030-12"
				(at 35.56 -10.16 0)
				(effects
					(font
						(size 1.27 1.27)
						(thickness 0.15)
					)
					(justify left bottom)
					(hide yes)
				)
			)
			(property "Datasheet" "https://www.diodes.com/assets/Datasheets/AP62600.pdf"
				(at 35.56 -12.7 0)
				(effects
					(font
						(size 1.27 1.27)
						(thickness 0.15)
					)
					(justify left bottom)
					(hide yes)
				)
			)
			(property "Description" "Buck Switching Regulator IC Positive Fixed 0.6V 1 Output 6A 12-VFQFN"
				(at 0 0 0)
				(effects
					(font
						(size 1.27 1.27)
					)
					(hide yes)
				)
			)
			(property "MPN" "AP62600SJ-7"
				(at 35.56 -5.08 0)
				(effects
					(font
						(size 1.27 1.27)
						(thickness 0.15)
					)
					(justify left bottom)
				)
			)
			(property "Manufacturer" "Diodes Incorporated"
				(at 35.56 -15.24 0)
				(effects
					(font
						(size 1.27 1.27)
						(thickness 0.15)
					)
					(justify left bottom)
					(hide yes)
				)
			)
			(property "Author" "Antmicro"
				(at 35.56 -17.78 0)
				(effects
					(font
						(size 1.27 1.27)
						(thickness 0.15)
					)
					(justify left bottom)
					(hide yes)
				)
			)
			(property "License" "Apache-2.0"
				(at 35.56 -20.32 0)
				(effects
					(font
						(size 1.27 1.27)
						(thickness 0.15)
					)
					(justify left bottom)
					(hide yes)
				)
			)
			(symbol "AP62600SJ-7_1_1"
				(rectangle
					(start 2.54 2.54)
					(end 20.32 -27.94)
					(stroke
						(width 0.254)
						(type default)
					)
					(fill
						(type background)
					)
				)
				(pin power_in line
					(at 0 0 0)
					(length 2.54)
					(name "VIN"
						(effects
							(font
								(size 1.27 1.27)
							)
						)
					)
					(number "2"
						(effects
							(font
								(size 1.27 1.27)
							)
						)
					)
				)
				(pin input line
					(at 0 -12.7 0)
					(length 2.54)
					(name "EN"
						(effects
							(font
								(size 1.27 1.27)
							)
						)
					)
					(number "3"
						(effects
							(font
								(size 1.27 1.27)
							)
						)
					)
				)
				(pin open_collector line
					(at 0 -15.24 0)
					(length 2.54)
					(name "PG"
						(effects
							(font
								(size 1.27 1.27)
							)
						)
					)
					(number "6"
						(effects
							(font
								(size 1.27 1.27)
							)
						)
					)
				)
				(pin input line
					(at 0 -17.78 0)
					(length 2.54)
					(name "FSEL"
						(effects
							(font
								(size 1.27 1.27)
							)
						)
					)
					(number "5"
						(effects
							(font
								(size 1.27 1.27)
							)
						)
					)
				)
				(pin input line
					(at 0 -20.32 0)
					(length 2.54)
					(name "MODE"
						(effects
							(font
								(size 1.27 1.27)
							)
						)
					)
					(number "4"
						(effects
							(font
								(size 1.27 1.27)
							)
						)
					)
				)
				(pin input line
					(at 0 -22.86 0)
					(length 2.54)
					(name "SS/TR"
						(effects
							(font
								(size 1.27 1.27)
							)
						)
					)
					(number "10"
						(effects
							(font
								(size 1.27 1.27)
							)
						)
					)
				)
				(pin passive line
					(at 0 -25.4 0)
					(length 2.54)
					(name "GND"
						(effects
							(font
								(size 1.27 1.27)
							)
						)
					)
					(number "11"
						(effects
							(font
								(size 1.27 1.27)
							)
						)
					)
				)
				(pin output line
					(at 22.86 0 180)
					(length 2.54)
					(name "SW"
						(effects
							(font
								(size 1.27 1.27)
							)
						)
					)
					(number "8"
						(effects
							(font
								(size 1.27 1.27)
							)
						)
					)
				)
				(pin input line
					(at 22.86 -7.62 180)
					(length 2.54)
					(name "BST"
						(effects
							(font
								(size 1.27 1.27)
							)
						)
					)
					(number "7"
						(effects
							(font
								(size 1.27 1.27)
							)
						)
					)
				)
				(pin input line
					(at 22.86 -12.7 180)
					(length 2.54)
					(name "FB"
						(effects
							(font
								(size 1.27 1.27)
							)
						)
					)
					(number "12"
						(effects
							(font
								(size 1.27 1.27)
							)
						)
					)
				)
				(pin input line
					(at 22.86 -17.78 180)
					(length 2.54)
					(name "VCC"
						(effects
							(font
								(size 1.27 1.27)
							)
						)
					)
					(number "9"
						(effects
							(font
								(size 1.27 1.27)
							)
						)
					)
				)
				(pin passive line
					(at 22.86 -25.4 180)
					(length 2.54)
					(name "PGND"
						(effects
							(font
								(size 1.27 1.27)
							)
						)
					)
					(number "1"
						(effects
							(font
								(size 1.27 1.27)
							)
						)
					)
				)
			)
		)
	(symbol "antmicroDiodesRectifiersSingle:PDS760"
			(pin_numbers
				(hide yes)
			)
			(pin_names
				(hide yes)
			)
			(exclude_from_sim no)
			(in_bom yes)
			(on_board yes)
			(property "Reference" "D"
				(at 22.86 -5.08 0)
				(effects
					(font
						(size 1.27 1.27)
						(thickness 0.15)
					)
					(justify left bottom)
				)
			)
			(property "Value" "PDS760"
				(at 22.86 -7.62 0)
				(effects
					(font
						(size 1.27 1.27)
						(thickness 0.15)
					)
					(justify left bottom)
				)
			)
			(property "Footprint" "antmicro-footprints:PowerDI5"
				(at 22.86 -10.16 0)
				(effects
					(font
						(size 1.27 1.27)
						(thickness 0.15)
					)
					(justify left bottom)
					(hide yes)
				)
			)
			(property "Datasheet" "https://www.diodes.com/assets/Datasheets/ds30470.pdf"
				(at 22.86 -12.7 0)
				(effects
					(font
						(size 1.27 1.27)
						(thickness 0.15)
					)
					(justify left bottom)
					(hide yes)
				)
			)
			(property "Description" "PDS760 Series 60 V 7 A Surface Mount Schottky Barrier Rectifier - PowerDI-5"
				(at 0 0 0)
				(effects
					(font
						(size 1.27 1.27)
					)
					(hide yes)
				)
			)
			(property "Manufacturer" "Diodes Incorporated"
				(at 22.86 -15.24 0)
				(effects
					(font
						(size 1.27 1.27)
						(thickness 0.15)
					)
					(justify left bottom)
					(hide yes)
				)
			)
			(property "MPN" "PDS760-13"
				(at 22.86 -17.78 0)
				(effects
					(font
						(size 1.27 1.27)
						(thickness 0.15)
					)
					(justify left bottom)
					(hide yes)
				)
			)
			(property "Author" "Antmicro"
				(at 22.86 -20.32 0)
				(effects
					(font
						(size 1.27 1.27)
						(thickness 0.15)
					)
					(justify left bottom)
					(hide yes)
				)
			)
			(property "License" "Apache-2.0"
				(at 22.86 -22.86 0)
				(effects
					(font
						(size 1.27 1.27)
						(thickness 0.15)
					)
					(justify left bottom)
					(hide yes)
				)
			)
			(property "ki_keywords" "PDS760 Series 60 V 7 A Surface Mount Schottky Barrier Rectifier - PowerDI-5"
				(at 0 0 0)
				(effects
					(font
						(size 1.27 1.27)
					)
					(hide yes)
				)
			)
			(symbol "PDS760_1_1"
				(polyline
					(pts
						(xy 2.54 1.27) (xy 2.54 -1.27) (xy 5.08 0) (xy 2.54 1.27)
					)
					(stroke
						(width 0.254)
						(type default)
					)
					(fill
						(type outline)
					)
				)
				(polyline
					(pts
						(xy 4.572 -1.016) (xy 4.572 -1.3462)
					)
					(stroke
						(width 0.254)
						(type default)
					)
					(fill
						(type background)
					)
				)
				(polyline
					(pts
						(xy 5.588 1.1938) (xy 5.588 0.8128)
					)
					(stroke
						(width 0.254)
						(type default)
					)
					(fill
						(type background)
					)
				)
				(polyline
					(pts
						(xy 5.588 1.1938) (xy 5.08 1.1938) (xy 5.08 -1.3462) (xy 4.572 -1.3462)
					)
					(stroke
						(width 0.254)
						(type default)
					)
					(fill
						(type none)
					)
				)
				(pin passive line
					(at 0 0 0)
					(length 2.54)
					(name "A"
						(effects
							(font
								(size 1.27 1.27)
							)
						)
					)
					(number "A"
						(effects
							(font
								(size 1.27 1.27)
							)
						)
					)
				)
				(pin passive line
					(at 7.62 0 180)
					(length 2.54)
					(name "C"
						(effects
							(font
								(size 1.27 1.27)
							)
						)
					)
					(number "C"
						(effects
							(font
								(size 1.27 1.27)
							)
						)
					)
				)
			)
		)
	(symbol "antmicroFPGAChips:XC7K70T-FBG484"
			(exclude_from_sim no)
			(in_bom yes)
			(on_board yes)
			(property "Reference" "U"
				(at 53.34 0 0)
				(effects
					(font
						(size 1.27 1.27)
						(thickness 0.15)
					)
					(justify left bottom)
				)
			)
			(property "Value" "XC7K70T-FBG484"
				(at 53.34 -5.08 0)
				(effects
					(font
						(size 1.27 1.27)
						(thickness 0.15)
					)
					(justify left bottom)
					(hide yes)
				)
			)
			(property "Footprint" "antmicro-footprints:BGA-484_23x23mm_Layout22x22_P1mm_FBG484"
				(at 53.34 -7.62 0)
				(effects
					(font
						(size 1.27 1.27)
						(thickness 0.15)
					)
					(justify left bottom)
					(hide yes)
				)
			)
			(property "Datasheet" "https://docs.xilinx.com/v/u/en-US/ds182_Kintex_7_Data_Sheet"
				(at 53.34 -10.16 0)
				(effects
					(font
						(size 1.27 1.27)
						(thickness 0.15)
					)
					(justify left bottom)
					(hide yes)
				)
			)
			(property "Description" "Kintex®-7 Field Programmable Gate Array (FPGA) IC 285 484-BBGA, FCBGA"
				(at 0 0 0)
				(effects
					(font
						(size 1.27 1.27)
					)
					(hide yes)
				)
			)
			(property "Manufacturer" "AMD-Xilinx"
				(at 53.34 -12.7 0)
				(effects
					(font
						(size 1.27 1.27)
						(thickness 0.15)
					)
					(justify left bottom)
					(hide yes)
				)
			)
			(property "MPN" "XC7K70T-1FBG484C"
				(at 53.34 -2.54 0)
				(effects
					(font
						(size 1.27 1.27)
						(thickness 0.15)
					)
					(justify left bottom)
				)
			)
			(property "Author" "Antmicro"
				(at 53.34 -15.24 0)
				(effects
					(font
						(size 1.27 1.27)
						(thickness 0.15)
					)
					(justify left bottom)
					(hide yes)
				)
			)
			(property "License" "Apache-2.0"
				(at 53.34 -17.78 0)
				(effects
					(font
						(size 1.27 1.27)
						(thickness 0.15)
					)
					(justify left bottom)
					(hide yes)
				)
			)
			(property "ki_locked" ""
				(at 0 0 0)
				(effects
					(font
						(size 1.27 1.27)
					)
				)
			)
			(property "ki_keywords" "SMT, MICROCONTROLLER, IC, FPGA"
				(at 0 0 0)
				(effects
					(font
						(size 1.27 1.27)
					)
					(hide yes)
				)
			)
			(symbol "XC7K70T-FBG484_1_1"
				(rectangle
					(start 5.08 5.08)
					(end 25.4 -55.88)
					(stroke
						(width 0.254)
						(type default)
					)
					(fill
						(type background)
					)
				)
				(text "POWER"
					(at 11.43 2.54 0)
					(effects
						(font
							(size 1.27 1.27)
							(thickness 0.15)
						)
						(justify left bottom)
					)
				)
				(pin power_in line
					(at 0 0 0)
					(length 5.08)
					(name "VCCO_0"
						(effects
							(font
								(size 1.27 1.27)
							)
						)
					)
					(number "J7"
						(effects
							(font
								(size 1.27 1.27)
							)
						)
					)
				)
				(pin passive line
					(at 0 0 0)
					(length 5.08)
					(hide yes)
					(name "VCCO_0"
						(effects
							(font
								(size 1.27 1.27)
							)
						)
					)
					(number "N7"
						(effects
							(font
								(size 1.27 1.27)
							)
						)
					)
				)
				(pin power_in line
					(at 0 -2.54 0)
					(length 5.08)
					(name "VCCAUX"
						(effects
							(font
								(size 1.27 1.27)
							)
						)
					)
					(number "K10"
						(effects
							(font
								(size 1.27 1.27)
							)
						)
					)
				)
				(pin passive line
					(at 0 -2.54 0)
					(length 5.08)
					(hide yes)
					(name "VCCAUX"
						(effects
							(font
								(size 1.27 1.27)
							)
						)
					)
					(number "M10"
						(effects
							(font
								(size 1.27 1.27)
							)
						)
					)
				)
				(pin passive line
					(at 0 -2.54 0)
					(length 5.08)
					(hide yes)
					(name "VCCAUX"
						(effects
							(font
								(size 1.27 1.27)
							)
						)
					)
					(number "P10"
						(effects
							(font
								(size 1.27 1.27)
							)
						)
					)
				)
				(pin passive line
					(at 0 -2.54 0)
					(length 5.08)
					(hide yes)
					(name "VCCAUX"
						(effects
							(font
								(size 1.27 1.27)
							)
						)
					)
					(number "P12"
						(effects
							(font
								(size 1.27 1.27)
							)
						)
					)
				)
				(pin passive line
					(at 0 -2.54 0)
					(length 5.08)
					(hide yes)
					(name "VCCAUX"
						(effects
							(font
								(size 1.27 1.27)
							)
						)
					)
					(number "P8"
						(effects
							(font
								(size 1.27 1.27)
							)
						)
					)
				)
				(pin passive line
					(at 0 -2.54 0)
					(length 5.08)
					(hide yes)
					(name "VCCAUX"
						(effects
							(font
								(size 1.27 1.27)
							)
						)
					)
					(number "R11"
						(effects
							(font
								(size 1.27 1.27)
							)
						)
					)
				)
				(pin passive line
					(at 0 -2.54 0)
					(length 5.08)
					(hide yes)
					(name "VCCAUX"
						(effects
							(font
								(size 1.27 1.27)
							)
						)
					)
					(number "R9"
						(effects
							(font
								(size 1.27 1.27)
							)
						)
					)
				)
				(pin power_in line
					(at 0 -5.08 0)
					(length 5.08)
					(name "VCCINT"
						(effects
							(font
								(size 1.27 1.27)
							)
						)
					)
					(number "J11"
						(effects
							(font
								(size 1.27 1.27)
							)
						)
					)
				)
				(pin passive line
					(at 0 -5.08 0)
					(length 5.08)
					(hide yes)
					(name "VCCINT"
						(effects
							(font
								(size 1.27 1.27)
							)
						)
					)
					(number "J13"
						(effects
							(font
								(size 1.27 1.27)
							)
						)
					)
				)
				(pin passive line
					(at 0 -5.08 0)
					(length 5.08)
					(hide yes)
					(name "VCCINT"
						(effects
							(font
								(size 1.27 1.27)
							)
						)
					)
					(number "J15"
						(effects
							(font
								(size 1.27 1.27)
							)
						)
					)
				)
				(pin passive line
					(at 0 -5.08 0)
					(length 5.08)
					(hide yes)
					(name "VCCINT"
						(effects
							(font
								(size 1.27 1.27)
							)
						)
					)
					(number "J9"
						(effects
							(font
								(size 1.27 1.27)
							)
						)
					)
				)
				(pin passive line
					(at 0 -5.08 0)
					(length 5.08)
					(hide yes)
					(name "VCCINT"
						(effects
							(font
								(size 1.27 1.27)
							)
						)
					)
					(number "K14"
						(effects
							(font
								(size 1.27 1.27)
							)
						)
					)
				)
				(pin passive line
					(at 0 -5.08 0)
					(length 5.08)
					(hide yes)
					(name "VCCINT"
						(effects
							(font
								(size 1.27 1.27)
							)
						)
					)
					(number "K8"
						(effects
							(font
								(size 1.27 1.27)
							)
						)
					)
				)
				(pin passive line
					(at 0 -5.08 0)
					(length 5.08)
					(hide yes)
					(name "VCCINT"
						(effects
							(font
								(size 1.27 1.27)
							)
						)
					)
					(number "L15"
						(effects
							(font
								(size 1.27 1.27)
							)
						)
					)
				)
				(pin passive line
					(at 0 -5.08 0)
					(length 5.08)
					(hide yes)
					(name "VCCINT"
						(effects
							(font
								(size 1.27 1.27)
							)
						)
					)
					(number "L9"
						(effects
							(font
								(size 1.27 1.27)
							)
						)
					)
				)
				(pin passive line
					(at 0 -5.08 0)
					(length 5.08)
					(hide yes)
					(name "VCCINT"
						(effects
							(font
								(size 1.27 1.27)
							)
						)
					)
					(number "M14"
						(effects
							(font
								(size 1.27 1.27)
							)
						)
					)
				)
				(pin passive line
					(at 0 -5.08 0)
					(length 5.08)
					(hide yes)
					(name "VCCINT"
						(effects
							(font
								(size 1.27 1.27)
							)
						)
					)
					(number "M8"
						(effects
							(font
								(size 1.27 1.27)
							)
						)
					)
				)
				(pin passive line
					(at 0 -5.08 0)
					(length 5.08)
					(hide yes)
					(name "VCCINT"
						(effects
							(font
								(size 1.27 1.27)
							)
						)
					)
					(number "N15"
						(effects
							(font
								(size 1.27 1.27)
							)
						)
					)
				)
				(pin passive line
					(at 0 -5.08 0)
					(length 5.08)
					(hide yes)
					(name "VCCINT"
						(effects
							(font
								(size 1.27 1.27)
							)
						)
					)
					(number "N9"
						(effects
							(font
								(size 1.27 1.27)
							)
						)
					)
				)
				(pin passive line
					(at 0 -5.08 0)
					(length 5.08)
					(hide yes)
					(name "VCCINT"
						(effects
							(font
								(size 1.27 1.27)
							)
						)
					)
					(number "P14"
						(effects
							(font
								(size 1.27 1.27)
							)
						)
					)
				)
				(pin passive line
					(at 0 -5.08 0)
					(length 5.08)
					(hide yes)
					(name "VCCINT"
						(effects
							(font
								(size 1.27 1.27)
							)
						)
					)
					(number "R15"
						(effects
							(font
								(size 1.27 1.27)
							)
						)
					)
				)
				(pin power_in line
					(at 0 -7.62 0)
					(length 5.08)
					(name "VCCBATT_0"
						(effects
							(font
								(size 1.27 1.27)
							)
						)
					)
					(number "P7"
						(effects
							(font
								(size 1.27 1.27)
							)
						)
					)
				)
				(pin power_in line
					(at 0 -10.16 0)
					(length 5.08)
					(name "VCCBRAM"
						(effects
							(font
								(size 1.27 1.27)
							)
						)
					)
					(number "L13"
						(effects
							(font
								(size 1.27 1.27)
							)
						)
					)
				)
				(pin passive line
					(at 0 -10.16 0)
					(length 5.08)
					(hide yes)
					(name "VCCBRAM"
						(effects
							(font
								(size 1.27 1.27)
							)
						)
					)
					(number "N13"
						(effects
							(font
								(size 1.27 1.27)
							)
						)
					)
				)
				(pin passive line
					(at 0 -10.16 0)
					(length 5.08)
					(hide yes)
					(name "VCCBRAM"
						(effects
							(font
								(size 1.27 1.27)
							)
						)
					)
					(number "R13"
						(effects
							(font
								(size 1.27 1.27)
							)
						)
					)
				)
				(pin power_in line
					(at 0 -12.7 0)
					(length 5.08)
					(name "VCCADC_0"
						(effects
							(font
								(size 1.27 1.27)
							)
						)
					)
					(number "K12"
						(effects
							(font
								(size 1.27 1.27)
							)
						)
					)
				)
				(pin power_in line
					(at 0 -17.78 0)
					(length 5.08)
					(name "MGTAVCC"
						(effects
							(font
								(size 1.27 1.27)
							)
						)
					)
					(number "A6"
						(effects
							(font
								(size 1.27 1.27)
							)
						)
					)
				)
				(pin passive line
					(at 0 -17.78 0)
					(length 5.08)
					(hide yes)
					(name "MGTAVCC"
						(effects
							(font
								(size 1.27 1.27)
							)
						)
					)
					(number "C6"
						(effects
							(font
								(size 1.27 1.27)
							)
						)
					)
				)
				(pin passive line
					(at 0 -17.78 0)
					(length 5.08)
					(hide yes)
					(name "MGTAVCC"
						(effects
							(font
								(size 1.27 1.27)
							)
						)
					)
					(number "E6"
						(effects
							(font
								(size 1.27 1.27)
							)
						)
					)
				)
				(pin passive line
					(at 0 -17.78 0)
					(length 5.08)
					(hide yes)
					(name "MGTAVCC"
						(effects
							(font
								(size 1.27 1.27)
							)
						)
					)
					(number "G6"
						(effects
							(font
								(size 1.27 1.27)
							)
						)
					)
				)
				(pin power_in line
					(at 0 -20.32 0)
					(length 5.08)
					(name "MGTAVTT"
						(effects
							(font
								(size 1.27 1.27)
							)
						)
					)
					(number "A2"
						(effects
							(font
								(size 1.27 1.27)
							)
						)
					)
				)
				(pin passive line
					(at 0 -20.32 0)
					(length 5.08)
					(hide yes)
					(name "MGTAVTT"
						(effects
							(font
								(size 1.27 1.27)
							)
						)
					)
					(number "C2"
						(effects
							(font
								(size 1.27 1.27)
							)
						)
					)
				)
				(pin passive line
					(at 0 -20.32 0)
					(length 5.08)
					(hide yes)
					(name "MGTAVTT"
						(effects
							(font
								(size 1.27 1.27)
							)
						)
					)
					(number "E2"
						(effects
							(font
								(size 1.27 1.27)
							)
						)
					)
				)
				(pin passive line
					(at 0 -20.32 0)
					(length 5.08)
					(hide yes)
					(name "MGTAVTT"
						(effects
							(font
								(size 1.27 1.27)
							)
						)
					)
					(number "G2"
						(effects
							(font
								(size 1.27 1.27)
							)
						)
					)
				)
				(pin power_in line
					(at 0 -22.86 0)
					(length 5.08)
					(name "MGTVCCAUX"
						(effects
							(font
								(size 1.27 1.27)
							)
						)
					)
					(number "J4"
						(effects
							(font
								(size 1.27 1.27)
							)
						)
					)
				)
				(pin power_in line
					(at 0 -25.4 0)
					(length 5.08)
					(name "MGTAVTTRCAL_115"
						(effects
							(font
								(size 1.27 1.27)
							)
						)
					)
					(number "H1"
						(effects
							(font
								(size 1.27 1.27)
							)
						)
					)
				)
				(pin power_in line
					(at 0 -27.94 0)
					(length 5.08)
					(name "MGTRREF_115"
						(effects
							(font
								(size 1.27 1.27)
							)
						)
					)
					(number "H2"
						(effects
							(font
								(size 1.27 1.27)
							)
						)
					)
				)
				(pin power_in line
					(at 0 -33.02 0)
					(length 5.08)
					(name "VCCO_34"
						(effects
							(font
								(size 1.27 1.27)
							)
						)
					)
					(number "AB4"
						(effects
							(font
								(size 1.27 1.27)
							)
						)
					)
				)
				(pin passive line
					(at 0 -33.02 0)
					(length 5.08)
					(hide yes)
					(name "VCCO_34"
						(effects
							(font
								(size 1.27 1.27)
							)
						)
					)
					(number "M4"
						(effects
							(font
								(size 1.27 1.27)
							)
						)
					)
				)
				(pin passive line
					(at 0 -33.02 0)
					(length 5.08)
					(hide yes)
					(name "VCCO_34"
						(effects
							(font
								(size 1.27 1.27)
							)
						)
					)
					(number "N1"
						(effects
							(font
								(size 1.27 1.27)
							)
						)
					)
				)
				(pin passive line
					(at 0 -33.02 0)
					(length 5.08)
					(hide yes)
					(name "VCCO_34"
						(effects
							(font
								(size 1.27 1.27)
							)
						)
					)
					(number "R5"
						(effects
							(font
								(size 1.27 1.27)
							)
						)
					)
				)
				(pin passive line
					(at 0 -33.02 0)
					(length 5.08)
					(hide yes)
					(name "VCCO_34"
						(effects
							(font
								(size 1.27 1.27)
							)
						)
					)
					(number "T2"
						(effects
							(font
								(size 1.27 1.27)
							)
						)
					)
				)
				(pin passive line
					(at 0 -33.02 0)
					(length 5.08)
					(hide yes)
					(name "VCCO_34"
						(effects
							(font
								(size 1.27 1.27)
							)
						)
					)
					(number "W3"
						(effects
							(font
								(size 1.27 1.27)
							)
						)
					)
				)
				(pin power_in line
					(at 0 -35.56 0)
					(length 5.08)
					(name "VCCO_33"
						(effects
							(font
								(size 1.27 1.27)
							)
						)
					)
					(number "AA7"
						(effects
							(font
								(size 1.27 1.27)
							)
						)
					)
				)
				(pin passive line
					(at 0 -35.56 0)
					(length 5.08)
					(hide yes)
					(name "VCCO_33"
						(effects
							(font
								(size 1.27 1.27)
							)
						)
					)
					(number "T12"
						(effects
							(font
								(size 1.27 1.27)
							)
						)
					)
				)
				(pin passive line
					(at 0 -35.56 0)
					(length 5.08)
					(hide yes)
					(name "VCCO_33"
						(effects
							(font
								(size 1.27 1.27)
							)
						)
					)
					(number "U9"
						(effects
							(font
								(size 1.27 1.27)
							)
						)
					)
				)
				(pin passive line
					(at 0 -35.56 0)
					(length 5.08)
					(hide yes)
					(name "VCCO_33"
						(effects
							(font
								(size 1.27 1.27)
							)
						)
					)
					(number "V6"
						(effects
							(font
								(size 1.27 1.27)
							)
						)
					)
				)
				(pin passive line
					(at 0 -35.56 0)
					(length 5.08)
					(hide yes)
					(name "VCCO_33"
						(effects
							(font
								(size 1.27 1.27)
							)
						)
					)
					(number "W13"
						(effects
							(font
								(size 1.27 1.27)
							)
						)
					)
				)
				(pin passive line
					(at 0 -35.56 0)
					(length 5.08)
					(hide yes)
					(name "VCCO_33"
						(effects
							(font
								(size 1.27 1.27)
							)
						)
					)
					(number "Y10"
						(effects
							(font
								(size 1.27 1.27)
							)
						)
					)
				)
				(pin power_in line
					(at 0 -38.1 0)
					(length 5.08)
					(name "VCCO_16"
						(effects
							(font
								(size 1.27 1.27)
							)
						)
					)
					(number "C11"
						(effects
							(font
								(size 1.27 1.27)
							)
						)
					)
				)
				(pin passive line
					(at 0 -38.1 0)
					(length 5.08)
					(hide yes)
					(name "VCCO_16"
						(effects
							(font
								(size 1.27 1.27)
							)
						)
					)
					(number "D8"
						(effects
							(font
								(size 1.27 1.27)
							)
						)
					)
				)
				(pin passive line
					(at 0 -38.1 0)
					(length 5.08)
					(hide yes)
					(name "VCCO_16"
						(effects
							(font
								(size 1.27 1.27)
							)
						)
					)
					(number "F12"
						(effects
							(font
								(size 1.27 1.27)
							)
						)
					)
				)
				(pin passive line
					(at 0 -38.1 0)
					(length 5.08)
					(hide yes)
					(name "VCCO_16"
						(effects
							(font
								(size 1.27 1.27)
							)
						)
					)
					(number "G9"
						(effects
							(font
								(size 1.27 1.27)
							)
						)
					)
				)
				(pin power_in line
					(at 0 -40.64 0)
					(length 5.08)
					(name "VCCO_15"
						(effects
							(font
								(size 1.27 1.27)
							)
						)
					)
					(number "A17"
						(effects
							(font
								(size 1.27 1.27)
							)
						)
					)
				)
				(pin passive line
					(at 0 -40.64 0)
					(length 5.08)
					(hide yes)
					(name "VCCO_15"
						(effects
							(font
								(size 1.27 1.27)
							)
						)
					)
					(number "B14"
						(effects
							(font
								(size 1.27 1.27)
							)
						)
					)
				)
				(pin passive line
					(at 0 -40.64 0)
					(length 5.08)
					(hide yes)
					(name "VCCO_15"
						(effects
							(font
								(size 1.27 1.27)
							)
						)
					)
					(number "C21"
						(effects
							(font
								(size 1.27 1.27)
							)
						)
					)
				)
				(pin passive line
					(at 0 -40.64 0)
					(length 5.08)
					(hide yes)
					(name "VCCO_15"
						(effects
							(font
								(size 1.27 1.27)
							)
						)
					)
					(number "D18"
						(effects
							(font
								(size 1.27 1.27)
							)
						)
					)
				)
				(pin passive line
					(at 0 -40.64 0)
					(length 5.08)
					(hide yes)
					(name "VCCO_15"
						(effects
							(font
								(size 1.27 1.27)
							)
						)
					)
					(number "E15"
						(effects
							(font
								(size 1.27 1.27)
							)
						)
					)
				)
				(pin passive line
					(at 0 -40.64 0)
					(length 5.08)
					(hide yes)
					(name "VCCO_15"
						(effects
							(font
								(size 1.27 1.27)
							)
						)
					)
					(number "H16"
						(effects
							(font
								(size 1.27 1.27)
							)
						)
					)
				)
				(pin power_in line
					(at 0 -43.18 0)
					(length 5.08)
					(name "VCCO_14"
						(effects
							(font
								(size 1.27 1.27)
							)
						)
					)
					(number "F22"
						(effects
							(font
								(size 1.27 1.27)
							)
						)
					)
				)
				(pin passive line
					(at 0 -43.18 0)
					(length 5.08)
					(hide yes)
					(name "VCCO_14"
						(effects
							(font
								(size 1.27 1.27)
							)
						)
					)
					(number "G19"
						(effects
							(font
								(size 1.27 1.27)
							)
						)
					)
				)
				(pin passive line
					(at 0 -43.18 0)
					(length 5.08)
					(hide yes)
					(name "VCCO_14"
						(effects
							(font
								(size 1.27 1.27)
							)
						)
					)
					(number "K20"
						(effects
							(font
								(size 1.27 1.27)
							)
						)
					)
				)
				(pin passive line
					(at 0 -43.18 0)
					(length 5.08)
					(hide yes)
					(name "VCCO_14"
						(effects
							(font
								(size 1.27 1.27)
							)
						)
					)
					(number "L17"
						(effects
							(font
								(size 1.27 1.27)
							)
						)
					)
				)
				(pin passive line
					(at 0 -43.18 0)
					(length 5.08)
					(hide yes)
					(name "VCCO_14"
						(effects
							(font
								(size 1.27 1.27)
							)
						)
					)
					(number "N21"
						(effects
							(font
								(size 1.27 1.27)
							)
						)
					)
				)
				(pin passive line
					(at 0 -43.18 0)
					(length 5.08)
					(hide yes)
					(name "VCCO_14"
						(effects
							(font
								(size 1.27 1.27)
							)
						)
					)
					(number "P18"
						(effects
							(font
								(size 1.27 1.27)
							)
						)
					)
				)
				(pin power_in line
					(at 0 -45.72 0)
					(length 5.08)
					(name "VCCO_13"
						(effects
							(font
								(size 1.27 1.27)
							)
						)
					)
					(number "AA17"
						(effects
							(font
								(size 1.27 1.27)
							)
						)
					)
				)
				(pin passive line
					(at 0 -45.72 0)
					(length 5.08)
					(hide yes)
					(name "VCCO_13"
						(effects
							(font
								(size 1.27 1.27)
							)
						)
					)
					(number "AB14"
						(effects
							(font
								(size 1.27 1.27)
							)
						)
					)
				)
				(pin passive line
					(at 0 -45.72 0)
					(length 5.08)
					(hide yes)
					(name "VCCO_13"
						(effects
							(font
								(size 1.27 1.27)
							)
						)
					)
					(number "T22"
						(effects
							(font
								(size 1.27 1.27)
							)
						)
					)
				)
				(pin passive line
					(at 0 -45.72 0)
					(length 5.08)
					(hide yes)
					(name "VCCO_13"
						(effects
							(font
								(size 1.27 1.27)
							)
						)
					)
					(number "U19"
						(effects
							(font
								(size 1.27 1.27)
							)
						)
					)
				)
				(pin passive line
					(at 0 -45.72 0)
					(length 5.08)
					(hide yes)
					(name "VCCO_13"
						(effects
							(font
								(size 1.27 1.27)
							)
						)
					)
					(number "V16"
						(effects
							(font
								(size 1.27 1.27)
							)
						)
					)
				)
				(pin passive line
					(at 0 -45.72 0)
					(length 5.08)
					(hide yes)
					(name "VCCO_13"
						(effects
							(font
								(size 1.27 1.27)
							)
						)
					)
					(number "Y20"
						(effects
							(font
								(size 1.27 1.27)
							)
						)
					)
				)
				(pin power_in line
					(at 0 -50.8 0)
					(length 5.08)
					(name "GNDADC_0"
						(effects
							(font
								(size 1.27 1.27)
							)
						)
					)
					(number "K11"
						(effects
							(font
								(size 1.27 1.27)
							)
						)
					)
				)
				(pin power_in line
					(at 0 -53.34 0)
					(length 5.08)
					(name "GND"
						(effects
							(font
								(size 1.27 1.27)
							)
						)
					)
					(number "A1"
						(effects
							(font
								(size 1.27 1.27)
							)
						)
					)
				)
				(pin passive line
					(at 0 -53.34 0)
					(length 5.08)
					(hide yes)
					(name "GND"
						(effects
							(font
								(size 1.27 1.27)
							)
						)
					)
					(number "A12"
						(effects
							(font
								(size 1.27 1.27)
							)
						)
					)
				)
				(pin passive line
					(at 0 -53.34 0)
					(length 5.08)
					(hide yes)
					(name "GND"
						(effects
							(font
								(size 1.27 1.27)
							)
						)
					)
					(number "A22"
						(effects
							(font
								(size 1.27 1.27)
							)
						)
					)
				)
				(pin passive line
					(at 0 -53.34 0)
					(length 5.08)
					(hide yes)
					(name "GND"
						(effects
							(font
								(size 1.27 1.27)
							)
						)
					)
					(number "A5"
						(effects
							(font
								(size 1.27 1.27)
							)
						)
					)
				)
				(pin passive line
					(at 0 -53.34 0)
					(length 5.08)
					(hide yes)
					(name "GND"
						(effects
							(font
								(size 1.27 1.27)
							)
						)
					)
					(number "A7"
						(effects
							(font
								(size 1.27 1.27)
							)
						)
					)
				)
				(pin passive line
					(at 0 -53.34 0)
					(length 5.08)
					(hide yes)
					(name "GND"
						(effects
							(font
								(size 1.27 1.27)
							)
						)
					)
					(number "AA12"
						(effects
							(font
								(size 1.27 1.27)
							)
						)
					)
				)
				(pin passive line
					(at 0 -53.34 0)
					(length 5.08)
					(hide yes)
					(name "GND"
						(effects
							(font
								(size 1.27 1.27)
							)
						)
					)
					(number "AA2"
						(effects
							(font
								(size 1.27 1.27)
							)
						)
					)
				)
				(pin passive line
					(at 0 -53.34 0)
					(length 5.08)
					(hide yes)
					(name "GND"
						(effects
							(font
								(size 1.27 1.27)
							)
						)
					)
					(number "AA22"
						(effects
							(font
								(size 1.27 1.27)
							)
						)
					)
				)
				(pin passive line
					(at 0 -53.34 0)
					(length 5.08)
					(hide yes)
					(name "GND"
						(effects
							(font
								(size 1.27 1.27)
							)
						)
					)
					(number "AB19"
						(effects
							(font
								(size 1.27 1.27)
							)
						)
					)
				)
				(pin passive line
					(at 0 -53.34 0)
					(length 5.08)
					(hide yes)
					(name "GND"
						(effects
							(font
								(size 1.27 1.27)
							)
						)
					)
					(number "AB9"
						(effects
							(font
								(size 1.27 1.27)
							)
						)
					)
				)
				(pin passive line
					(at 0 -53.34 0)
					(length 5.08)
					(hide yes)
					(name "GND"
						(effects
							(font
								(size 1.27 1.27)
							)
						)
					)
					(number "B19"
						(effects
							(font
								(size 1.27 1.27)
							)
						)
					)
				)
				(pin passive line
					(at 0 -53.34 0)
					(length 5.08)
					(hide yes)
					(name "GND"
						(effects
							(font
								(size 1.27 1.27)
							)
						)
					)
					(number "B3"
						(effects
							(font
								(size 1.27 1.27)
							)
						)
					)
				)
				(pin passive line
					(at 0 -53.34 0)
					(length 5.08)
					(hide yes)
					(name "GND"
						(effects
							(font
								(size 1.27 1.27)
							)
						)
					)
					(number "B4"
						(effects
							(font
								(size 1.27 1.27)
							)
						)
					)
				)
				(pin passive line
					(at 0 -53.34 0)
					(length 5.08)
					(hide yes)
					(name "GND"
						(effects
							(font
								(size 1.27 1.27)
							)
						)
					)
					(number "B7"
						(effects
							(font
								(size 1.27 1.27)
							)
						)
					)
				)
				(pin passive line
					(at 0 -53.34 0)
					(length 5.08)
					(hide yes)
					(name "GND"
						(effects
							(font
								(size 1.27 1.27)
							)
						)
					)
					(number "B9"
						(effects
							(font
								(size 1.27 1.27)
							)
						)
					)
				)
				(pin passive line
					(at 0 -53.34 0)
					(length 5.08)
					(hide yes)
					(name "GND"
						(effects
							(font
								(size 1.27 1.27)
							)
						)
					)
					(number "C1"
						(effects
							(font
								(size 1.27 1.27)
							)
						)
					)
				)
				(pin passive line
					(at 0 -53.34 0)
					(length 5.08)
					(hide yes)
					(name "GND"
						(effects
							(font
								(size 1.27 1.27)
							)
						)
					)
					(number "C16"
						(effects
							(font
								(size 1.27 1.27)
							)
						)
					)
				)
				(pin passive line
					(at 0 -53.34 0)
					(length 5.08)
					(hide yes)
					(name "GND"
						(effects
							(font
								(size 1.27 1.27)
							)
						)
					)
					(number "C5"
						(effects
							(font
								(size 1.27 1.27)
							)
						)
					)
				)
				(pin passive line
					(at 0 -53.34 0)
					(length 5.08)
					(hide yes)
					(name "GND"
						(effects
							(font
								(size 1.27 1.27)
							)
						)
					)
					(number "C7"
						(effects
							(font
								(size 1.27 1.27)
							)
						)
					)
				)
				(pin passive line
					(at 0 -53.34 0)
					(length 5.08)
					(hide yes)
					(name "GND"
						(effects
							(font
								(size 1.27 1.27)
							)
						)
					)
					(number "D13"
						(effects
							(font
								(size 1.27 1.27)
							)
						)
					)
				)
				(pin passive line
					(at 0 -53.34 0)
					(length 5.08)
					(hide yes)
					(name "GND"
						(effects
							(font
								(size 1.27 1.27)
							)
						)
					)
					(number "D3"
						(effects
							(font
								(size 1.27 1.27)
							)
						)
					)
				)
				(pin passive line
					(at 0 -53.34 0)
					(length 5.08)
					(hide yes)
					(name "GND"
						(effects
							(font
								(size 1.27 1.27)
							)
						)
					)
					(number "D4"
						(effects
							(font
								(size 1.27 1.27)
							)
						)
					)
				)
				(pin passive line
					(at 0 -53.34 0)
					(length 5.08)
					(hide yes)
					(name "GND"
						(effects
							(font
								(size 1.27 1.27)
							)
						)
					)
					(number "D7"
						(effects
							(font
								(size 1.27 1.27)
							)
						)
					)
				)
				(pin passive line
					(at 0 -53.34 0)
					(length 5.08)
					(hide yes)
					(name "GND"
						(effects
							(font
								(size 1.27 1.27)
							)
						)
					)
					(number "E1"
						(effects
							(font
								(size 1.27 1.27)
							)
						)
					)
				)
				(pin passive line
					(at 0 -53.34 0)
					(length 5.08)
					(hide yes)
					(name "GND"
						(effects
							(font
								(size 1.27 1.27)
							)
						)
					)
					(number "E10"
						(effects
							(font
								(size 1.27 1.27)
							)
						)
					)
				)
				(pin passive line
					(at 0 -53.34 0)
					(length 5.08)
					(hide yes)
					(name "GND"
						(effects
							(font
								(size 1.27 1.27)
							)
						)
					)
					(number "E20"
						(effects
							(font
								(size 1.27 1.27)
							)
						)
					)
				)
				(pin passive line
					(at 0 -53.34 0)
					(length 5.08)
					(hide yes)
					(name "GND"
						(effects
							(font
								(size 1.27 1.27)
							)
						)
					)
					(number "E5"
						(effects
							(font
								(size 1.27 1.27)
							)
						)
					)
				)
				(pin passive line
					(at 0 -53.34 0)
					(length 5.08)
					(hide yes)
					(name "GND"
						(effects
							(font
								(size 1.27 1.27)
							)
						)
					)
					(number "E7"
						(effects
							(font
								(size 1.27 1.27)
							)
						)
					)
				)
				(pin passive line
					(at 0 -53.34 0)
					(length 5.08)
					(hide yes)
					(name "GND"
						(effects
							(font
								(size 1.27 1.27)
							)
						)
					)
					(number "F17"
						(effects
							(font
								(size 1.27 1.27)
							)
						)
					)
				)
				(pin passive line
					(at 0 -53.34 0)
					(length 5.08)
					(hide yes)
					(name "GND"
						(effects
							(font
								(size 1.27 1.27)
							)
						)
					)
					(number "F3"
						(effects
							(font
								(size 1.27 1.27)
							)
						)
					)
				)
				(pin passive line
					(at 0 -53.34 0)
					(length 5.08)
					(hide yes)
					(name "GND"
						(effects
							(font
								(size 1.27 1.27)
							)
						)
					)
					(number "F4"
						(effects
							(font
								(size 1.27 1.27)
							)
						)
					)
				)
				(pin passive line
					(at 0 -53.34 0)
					(length 5.08)
					(hide yes)
					(name "GND"
						(effects
							(font
								(size 1.27 1.27)
							)
						)
					)
					(number "F7"
						(effects
							(font
								(size 1.27 1.27)
							)
						)
					)
				)
				(pin passive line
					(at 0 -53.34 0)
					(length 5.08)
					(hide yes)
					(name "GND"
						(effects
							(font
								(size 1.27 1.27)
							)
						)
					)
					(number "G1"
						(effects
							(font
								(size 1.27 1.27)
							)
						)
					)
				)
				(pin passive line
					(at 0 -53.34 0)
					(length 5.08)
					(hide yes)
					(name "GND"
						(effects
							(font
								(size 1.27 1.27)
							)
						)
					)
					(number "G14"
						(effects
							(font
								(size 1.27 1.27)
							)
						)
					)
				)
				(pin passive line
					(at 0 -53.34 0)
					(length 5.08)
					(hide yes)
					(name "GND"
						(effects
							(font
								(size 1.27 1.27)
							)
						)
					)
					(number "G5"
						(effects
							(font
								(size 1.27 1.27)
							)
						)
					)
				)
				(pin passive line
					(at 0 -53.34 0)
					(length 5.08)
					(hide yes)
					(name "GND"
						(effects
							(font
								(size 1.27 1.27)
							)
						)
					)
					(number "H11"
						(effects
							(font
								(size 1.27 1.27)
							)
						)
					)
				)
				(pin passive line
					(at 0 -53.34 0)
					(length 5.08)
					(hide yes)
					(name "GND"
						(effects
							(font
								(size 1.27 1.27)
							)
						)
					)
					(number "H21"
						(effects
							(font
								(size 1.27 1.27)
							)
						)
					)
				)
				(pin passive line
					(at 0 -53.34 0)
					(length 5.08)
					(hide yes)
					(name "GND"
						(effects
							(font
								(size 1.27 1.27)
							)
						)
					)
					(number "H3"
						(effects
							(font
								(size 1.27 1.27)
							)
						)
					)
				)
				(pin passive line
					(at 0 -53.34 0)
					(length 5.08)
					(hide yes)
					(name "GND"
						(effects
							(font
								(size 1.27 1.27)
							)
						)
					)
					(number "H4"
						(effects
							(font
								(size 1.27 1.27)
							)
						)
					)
				)
				(pin passive line
					(at 0 -53.34 0)
					(length 5.08)
					(hide yes)
					(name "GND"
						(effects
							(font
								(size 1.27 1.27)
							)
						)
					)
					(number "H5"
						(effects
							(font
								(size 1.27 1.27)
							)
						)
					)
				)
				(pin passive line
					(at 0 -53.34 0)
					(length 5.08)
					(hide yes)
					(name "GND"
						(effects
							(font
								(size 1.27 1.27)
							)
						)
					)
					(number "J1"
						(effects
							(font
								(size 1.27 1.27)
							)
						)
					)
				)
				(pin passive line
					(at 0 -53.34 0)
					(length 5.08)
					(hide yes)
					(name "GND"
						(effects
							(font
								(size 1.27 1.27)
							)
						)
					)
					(number "J10"
						(effects
							(font
								(size 1.27 1.27)
							)
						)
					)
				)
				(pin passive line
					(at 0 -53.34 0)
					(length 5.08)
					(hide yes)
					(name "GND"
						(effects
							(font
								(size 1.27 1.27)
							)
						)
					)
					(number "J12"
						(effects
							(font
								(size 1.27 1.27)
							)
						)
					)
				)
				(pin passive line
					(at 0 -53.34 0)
					(length 5.08)
					(hide yes)
					(name "GND"
						(effects
							(font
								(size 1.27 1.27)
							)
						)
					)
					(number "J14"
						(effects
							(font
								(size 1.27 1.27)
							)
						)
					)
				)
				(pin passive line
					(at 0 -53.34 0)
					(length 5.08)
					(hide yes)
					(name "GND"
						(effects
							(font
								(size 1.27 1.27)
							)
						)
					)
					(number "J18"
						(effects
							(font
								(size 1.27 1.27)
							)
						)
					)
				)
				(pin passive line
					(at 0 -53.34 0)
					(length 5.08)
					(hide yes)
					(name "GND"
						(effects
							(font
								(size 1.27 1.27)
							)
						)
					)
					(number "J2"
						(effects
							(font
								(size 1.27 1.27)
							)
						)
					)
				)
				(pin passive line
					(at 0 -53.34 0)
					(length 5.08)
					(hide yes)
					(name "GND"
						(effects
							(font
								(size 1.27 1.27)
							)
						)
					)
					(number "J3"
						(effects
							(font
								(size 1.27 1.27)
							)
						)
					)
				)
				(pin passive line
					(at 0 -53.34 0)
					(length 5.08)
					(hide yes)
					(name "GND"
						(effects
							(font
								(size 1.27 1.27)
							)
						)
					)
					(number "J8"
						(effects
							(font
								(size 1.27 1.27)
							)
						)
					)
				)
				(pin passive line
					(at 0 -53.34 0)
					(length 5.08)
					(hide yes)
					(name "GND"
						(effects
							(font
								(size 1.27 1.27)
							)
						)
					)
					(number "K13"
						(effects
							(font
								(size 1.27 1.27)
							)
						)
					)
				)
				(pin passive line
					(at 0 -53.34 0)
					(length 5.08)
					(hide yes)
					(name "GND"
						(effects
							(font
								(size 1.27 1.27)
							)
						)
					)
					(number "K15"
						(effects
							(font
								(size 1.27 1.27)
							)
						)
					)
				)
				(pin passive line
					(at 0 -53.34 0)
					(length 5.08)
					(hide yes)
					(name "GND"
						(effects
							(font
								(size 1.27 1.27)
							)
						)
					)
					(number "K5"
						(effects
							(font
								(size 1.27 1.27)
							)
						)
					)
				)
				(pin passive line
					(at 0 -53.34 0)
					(length 5.08)
					(hide yes)
					(name "GND"
						(effects
							(font
								(size 1.27 1.27)
							)
						)
					)
					(number "K9"
						(effects
							(font
								(size 1.27 1.27)
							)
						)
					)
				)
				(pin passive line
					(at 0 -53.34 0)
					(length 5.08)
					(hide yes)
					(name "GND"
						(effects
							(font
								(size 1.27 1.27)
							)
						)
					)
					(number "L10"
						(effects
							(font
								(size 1.27 1.27)
							)
						)
					)
				)
				(pin passive line
					(at 0 -53.34 0)
					(length 5.08)
					(hide yes)
					(name "GND"
						(effects
							(font
								(size 1.27 1.27)
							)
						)
					)
					(number "L14"
						(effects
							(font
								(size 1.27 1.27)
							)
						)
					)
				)
				(pin passive line
					(at 0 -53.34 0)
					(length 5.08)
					(hide yes)
					(name "GND"
						(effects
							(font
								(size 1.27 1.27)
							)
						)
					)
					(number "L2"
						(effects
							(font
								(size 1.27 1.27)
							)
						)
					)
				)
				(pin passive line
					(at 0 -53.34 0)
					(length 5.08)
					(hide yes)
					(name "GND"
						(effects
							(font
								(size 1.27 1.27)
							)
						)
					)
					(number "L22"
						(effects
							(font
								(size 1.27 1.27)
							)
						)
					)
				)
				(pin passive line
					(at 0 -53.34 0)
					(length 5.08)
					(hide yes)
					(name "GND"
						(effects
							(font
								(size 1.27 1.27)
							)
						)
					)
					(number "L8"
						(effects
							(font
								(size 1.27 1.27)
							)
						)
					)
				)
				(pin passive line
					(at 0 -53.34 0)
					(length 5.08)
					(hide yes)
					(name "GND"
						(effects
							(font
								(size 1.27 1.27)
							)
						)
					)
					(number "M13"
						(effects
							(font
								(size 1.27 1.27)
							)
						)
					)
				)
				(pin passive line
					(at 0 -53.34 0)
					(length 5.08)
					(hide yes)
					(name "GND"
						(effects
							(font
								(size 1.27 1.27)
							)
						)
					)
					(number "M15"
						(effects
							(font
								(size 1.27 1.27)
							)
						)
					)
				)
				(pin passive line
					(at 0 -53.34 0)
					(length 5.08)
					(hide yes)
					(name "GND"
						(effects
							(font
								(size 1.27 1.27)
							)
						)
					)
					(number "M19"
						(effects
							(font
								(size 1.27 1.27)
							)
						)
					)
				)
				(pin passive line
					(at 0 -53.34 0)
					(length 5.08)
					(hide yes)
					(name "GND"
						(effects
							(font
								(size 1.27 1.27)
							)
						)
					)
					(number "M9"
						(effects
							(font
								(size 1.27 1.27)
							)
						)
					)
				)
				(pin passive line
					(at 0 -53.34 0)
					(length 5.08)
					(hide yes)
					(name "GND"
						(effects
							(font
								(size 1.27 1.27)
							)
						)
					)
					(number "N10"
						(effects
							(font
								(size 1.27 1.27)
							)
						)
					)
				)
				(pin passive line
					(at 0 -53.34 0)
					(length 5.08)
					(hide yes)
					(name "GND"
						(effects
							(font
								(size 1.27 1.27)
							)
						)
					)
					(number "N14"
						(effects
							(font
								(size 1.27 1.27)
							)
						)
					)
				)
				(pin passive line
					(at 0 -53.34 0)
					(length 5.08)
					(hide yes)
					(name "GND"
						(effects
							(font
								(size 1.27 1.27)
							)
						)
					)
					(number "N16"
						(effects
							(font
								(size 1.27 1.27)
							)
						)
					)
				)
				(pin passive line
					(at 0 -53.34 0)
					(length 5.08)
					(hide yes)
					(name "GND"
						(effects
							(font
								(size 1.27 1.27)
							)
						)
					)
					(number "N6"
						(effects
							(font
								(size 1.27 1.27)
							)
						)
					)
				)
				(pin passive line
					(at 0 -53.34 0)
					(length 5.08)
					(hide yes)
					(name "GND"
						(effects
							(font
								(size 1.27 1.27)
							)
						)
					)
					(number "N8"
						(effects
							(font
								(size 1.27 1.27)
							)
						)
					)
				)
				(pin passive line
					(at 0 -53.34 0)
					(length 5.08)
					(hide yes)
					(name "GND"
						(effects
							(font
								(size 1.27 1.27)
							)
						)
					)
					(number "P11"
						(effects
							(font
								(size 1.27 1.27)
							)
						)
					)
				)
				(pin passive line
					(at 0 -53.34 0)
					(length 5.08)
					(hide yes)
					(name "GND"
						(effects
							(font
								(size 1.27 1.27)
							)
						)
					)
					(number "P13"
						(effects
							(font
								(size 1.27 1.27)
							)
						)
					)
				)
				(pin passive line
					(at 0 -53.34 0)
					(length 5.08)
					(hide yes)
					(name "GND"
						(effects
							(font
								(size 1.27 1.27)
							)
						)
					)
					(number "P15"
						(effects
							(font
								(size 1.27 1.27)
							)
						)
					)
				)
				(pin passive line
					(at 0 -53.34 0)
					(length 5.08)
					(hide yes)
					(name "GND"
						(effects
							(font
								(size 1.27 1.27)
							)
						)
					)
					(number "P3"
						(effects
							(font
								(size 1.27 1.27)
							)
						)
					)
				)
				(pin passive line
					(at 0 -53.34 0)
					(length 5.08)
					(hide yes)
					(name "GND"
						(effects
							(font
								(size 1.27 1.27)
							)
						)
					)
					(number "P9"
						(effects
							(font
								(size 1.27 1.27)
							)
						)
					)
				)
				(pin passive line
					(at 0 -53.34 0)
					(length 5.08)
					(hide yes)
					(name "GND"
						(effects
							(font
								(size 1.27 1.27)
							)
						)
					)
					(number "R10"
						(effects
							(font
								(size 1.27 1.27)
							)
						)
					)
				)
				(pin passive line
					(at 0 -53.34 0)
					(length 5.08)
					(hide yes)
					(name "GND"
						(effects
							(font
								(size 1.27 1.27)
							)
						)
					)
					(number "R12"
						(effects
							(font
								(size 1.27 1.27)
							)
						)
					)
				)
				(pin passive line
					(at 0 -53.34 0)
					(length 5.08)
					(hide yes)
					(name "GND"
						(effects
							(font
								(size 1.27 1.27)
							)
						)
					)
					(number "R14"
						(effects
							(font
								(size 1.27 1.27)
							)
						)
					)
				)
				(pin passive line
					(at 0 -53.34 0)
					(length 5.08)
					(hide yes)
					(name "GND"
						(effects
							(font
								(size 1.27 1.27)
							)
						)
					)
					(number "R20"
						(effects
							(font
								(size 1.27 1.27)
							)
						)
					)
				)
				(pin passive line
					(at 0 -53.34 0)
					(length 5.08)
					(hide yes)
					(name "GND"
						(effects
							(font
								(size 1.27 1.27)
							)
						)
					)
					(number "R8"
						(effects
							(font
								(size 1.27 1.27)
							)
						)
					)
				)
				(pin passive line
					(at 0 -53.34 0)
					(length 5.08)
					(hide yes)
					(name "GND"
						(effects
							(font
								(size 1.27 1.27)
							)
						)
					)
					(number "T17"
						(effects
							(font
								(size 1.27 1.27)
							)
						)
					)
				)
				(pin passive line
					(at 0 -53.34 0)
					(length 5.08)
					(hide yes)
					(name "GND"
						(effects
							(font
								(size 1.27 1.27)
							)
						)
					)
					(number "T7"
						(effects
							(font
								(size 1.27 1.27)
							)
						)
					)
				)
				(pin passive line
					(at 0 -53.34 0)
					(length 5.08)
					(hide yes)
					(name "GND"
						(effects
							(font
								(size 1.27 1.27)
							)
						)
					)
					(number "U14"
						(effects
							(font
								(size 1.27 1.27)
							)
						)
					)
				)
				(pin passive line
					(at 0 -53.34 0)
					(length 5.08)
					(hide yes)
					(name "GND"
						(effects
							(font
								(size 1.27 1.27)
							)
						)
					)
					(number "U4"
						(effects
							(font
								(size 1.27 1.27)
							)
						)
					)
				)
				(pin passive line
					(at 0 -53.34 0)
					(length 5.08)
					(hide yes)
					(name "GND"
						(effects
							(font
								(size 1.27 1.27)
							)
						)
					)
					(number "V1"
						(effects
							(font
								(size 1.27 1.27)
							)
						)
					)
				)
				(pin passive line
					(at 0 -53.34 0)
					(length 5.08)
					(hide yes)
					(name "GND"
						(effects
							(font
								(size 1.27 1.27)
							)
						)
					)
					(number "V11"
						(effects
							(font
								(size 1.27 1.27)
							)
						)
					)
				)
				(pin passive line
					(at 0 -53.34 0)
					(length 5.08)
					(hide yes)
					(name "GND"
						(effects
							(font
								(size 1.27 1.27)
							)
						)
					)
					(number "V21"
						(effects
							(font
								(size 1.27 1.27)
							)
						)
					)
				)
				(pin passive line
					(at 0 -53.34 0)
					(length 5.08)
					(hide yes)
					(name "GND"
						(effects
							(font
								(size 1.27 1.27)
							)
						)
					)
					(number "W18"
						(effects
							(font
								(size 1.27 1.27)
							)
						)
					)
				)
				(pin passive line
					(at 0 -53.34 0)
					(length 5.08)
					(hide yes)
					(name "GND"
						(effects
							(font
								(size 1.27 1.27)
							)
						)
					)
					(number "W8"
						(effects
							(font
								(size 1.27 1.27)
							)
						)
					)
				)
				(pin passive line
					(at 0 -53.34 0)
					(length 5.08)
					(hide yes)
					(name "GND"
						(effects
							(font
								(size 1.27 1.27)
							)
						)
					)
					(number "Y15"
						(effects
							(font
								(size 1.27 1.27)
							)
						)
					)
				)
				(pin passive line
					(at 0 -53.34 0)
					(length 5.08)
					(hide yes)
					(name "GND"
						(effects
							(font
								(size 1.27 1.27)
							)
						)
					)
					(number "Y5"
						(effects
							(font
								(size 1.27 1.27)
							)
						)
					)
				)
			)
			(symbol "XC7K70T-FBG484_2_1"
				(rectangle
					(start 5.08 5.08)
					(end 25.4 -60.96)
					(stroke
						(width 0.254)
						(type default)
					)
					(fill
						(type background)
					)
				)
				(text "CONFIG"
					(at 11.43 2.54 0)
					(effects
						(font
							(size 1.27 1.27)
							(thickness 0.15)
						)
						(justify left bottom)
					)
				)
				(pin bidirectional line
					(at 0 0 0)
					(length 5.08)
					(name "TDI_0"
						(effects
							(font
								(size 1.27 1.27)
							)
						)
					)
					(number "K6"
						(effects
							(font
								(size 1.27 1.27)
							)
						)
					)
				)
				(pin bidirectional line
					(at 0 -2.54 0)
					(length 5.08)
					(name "TDO_0"
						(effects
							(font
								(size 1.27 1.27)
							)
						)
					)
					(number "J6"
						(effects
							(font
								(size 1.27 1.27)
							)
						)
					)
				)
				(pin bidirectional line
					(at 0 -5.08 0)
					(length 5.08)
					(name "TMS_0"
						(effects
							(font
								(size 1.27 1.27)
							)
						)
					)
					(number "L6"
						(effects
							(font
								(size 1.27 1.27)
							)
						)
					)
				)
				(pin bidirectional line
					(at 0 -7.62 0)
					(length 5.08)
					(name "TCK_0"
						(effects
							(font
								(size 1.27 1.27)
							)
						)
					)
					(number "K7"
						(effects
							(font
								(size 1.27 1.27)
							)
						)
					)
				)
				(pin bidirectional line
					(at 0 -12.7 0)
					(length 5.08)
					(name "CCLK_0"
						(effects
							(font
								(size 1.27 1.27)
							)
						)
					)
					(number "G7"
						(effects
							(font
								(size 1.27 1.27)
							)
						)
					)
				)
				(pin bidirectional line
					(at 0 -15.24 0)
					(length 5.08)
					(name "M0_0"
						(effects
							(font
								(size 1.27 1.27)
							)
						)
					)
					(number "H7"
						(effects
							(font
								(size 1.27 1.27)
							)
						)
					)
				)
				(pin bidirectional line
					(at 0 -17.78 0)
					(length 5.08)
					(name "M1_0"
						(effects
							(font
								(size 1.27 1.27)
							)
						)
					)
					(number "H6"
						(effects
							(font
								(size 1.27 1.27)
							)
						)
					)
				)
				(pin bidirectional line
					(at 0 -20.32 0)
					(length 5.08)
					(name "M2_0"
						(effects
							(font
								(size 1.27 1.27)
							)
						)
					)
					(number "J5"
						(effects
							(font
								(size 1.27 1.27)
							)
						)
					)
				)
				(pin bidirectional line
					(at 0 -25.4 0)
					(length 5.08)
					(name "DONE_0"
						(effects
							(font
								(size 1.27 1.27)
							)
						)
					)
					(number "P6"
						(effects
							(font
								(size 1.27 1.27)
							)
						)
					)
				)
				(pin bidirectional line
					(at 0 -27.94 0)
					(length 5.08)
					(name "INIT_B_0"
						(effects
							(font
								(size 1.27 1.27)
							)
						)
					)
					(number "L7"
						(effects
							(font
								(size 1.27 1.27)
							)
						)
					)
				)
				(pin bidirectional line
					(at 0 -30.48 0)
					(length 5.08)
					(name "PROGRAM_B_0"
						(effects
							(font
								(size 1.27 1.27)
							)
						)
					)
					(number "M6"
						(effects
							(font
								(size 1.27 1.27)
							)
						)
					)
				)
				(pin bidirectional line
					(at 0 -35.56 0)
					(length 5.08)
					(name "CFGBVS_0"
						(effects
							(font
								(size 1.27 1.27)
							)
						)
					)
					(number "M7"
						(effects
							(font
								(size 1.27 1.27)
							)
						)
					)
				)
				(pin bidirectional line
					(at 0 -40.64 0)
					(length 5.08)
					(name "VP_0"
						(effects
							(font
								(size 1.27 1.27)
							)
						)
					)
					(number "L12"
						(effects
							(font
								(size 1.27 1.27)
							)
						)
					)
				)
				(pin bidirectional line
					(at 0 -43.18 0)
					(length 5.08)
					(name "VN_0"
						(effects
							(font
								(size 1.27 1.27)
							)
						)
					)
					(number "M11"
						(effects
							(font
								(size 1.27 1.27)
							)
						)
					)
				)
				(pin bidirectional line
					(at 0 -48.26 0)
					(length 5.08)
					(name "VREFP_0"
						(effects
							(font
								(size 1.27 1.27)
							)
						)
					)
					(number "M12"
						(effects
							(font
								(size 1.27 1.27)
							)
						)
					)
				)
				(pin bidirectional line
					(at 0 -50.8 0)
					(length 5.08)
					(name "VREFN_0"
						(effects
							(font
								(size 1.27 1.27)
							)
						)
					)
					(number "L11"
						(effects
							(font
								(size 1.27 1.27)
							)
						)
					)
				)
				(pin bidirectional line
					(at 0 -55.88 0)
					(length 5.08)
					(name "DXP_0"
						(effects
							(font
								(size 1.27 1.27)
							)
						)
					)
					(number "N12"
						(effects
							(font
								(size 1.27 1.27)
							)
						)
					)
				)
				(pin bidirectional line
					(at 0 -58.42 0)
					(length 5.08)
					(name "DXN_0"
						(effects
							(font
								(size 1.27 1.27)
							)
						)
					)
					(number "N11"
						(effects
							(font
								(size 1.27 1.27)
							)
						)
					)
				)
			)
			(symbol "XC7K70T-FBG484_3_1"
				(rectangle
					(start 5.08 5.08)
					(end 24.13 -55.88)
					(stroke
						(width 0.254)
						(type default)
					)
					(fill
						(type background)
					)
				)
				(text "MGTX"
					(at 11.43 2.54 0)
					(effects
						(font
							(size 1.27 1.27)
							(thickness 0.15)
						)
						(justify left bottom)
					)
				)
				(pin bidirectional line
					(at 0 0 0)
					(length 5.08)
					(name "MGTXTXP0_115"
						(effects
							(font
								(size 1.27 1.27)
							)
						)
					)
					(number "F2"
						(effects
							(font
								(size 1.27 1.27)
							)
						)
					)
				)
				(pin bidirectional line
					(at 0 -2.54 0)
					(length 5.08)
					(name "MGTXTXN0_115"
						(effects
							(font
								(size 1.27 1.27)
							)
						)
					)
					(number "F1"
						(effects
							(font
								(size 1.27 1.27)
							)
						)
					)
				)
				(pin bidirectional line
					(at 0 -5.08 0)
					(length 5.08)
					(name "MGTXTXP1_115"
						(effects
							(font
								(size 1.27 1.27)
							)
						)
					)
					(number "D2"
						(effects
							(font
								(size 1.27 1.27)
							)
						)
					)
				)
				(pin bidirectional line
					(at 0 -7.62 0)
					(length 5.08)
					(name "MGTXTXN1_115"
						(effects
							(font
								(size 1.27 1.27)
							)
						)
					)
					(number "D1"
						(effects
							(font
								(size 1.27 1.27)
							)
						)
					)
				)
				(pin bidirectional line
					(at 0 -10.16 0)
					(length 5.08)
					(name "MGTXTXP2_115"
						(effects
							(font
								(size 1.27 1.27)
							)
						)
					)
					(number "B2"
						(effects
							(font
								(size 1.27 1.27)
							)
						)
					)
				)
				(pin bidirectional line
					(at 0 -12.7 0)
					(length 5.08)
					(name "MGTXTXN2_115"
						(effects
							(font
								(size 1.27 1.27)
							)
						)
					)
					(number "B1"
						(effects
							(font
								(size 1.27 1.27)
							)
						)
					)
				)
				(pin bidirectional line
					(at 0 -15.24 0)
					(length 5.08)
					(name "MGTXTXP3_115"
						(effects
							(font
								(size 1.27 1.27)
							)
						)
					)
					(number "A4"
						(effects
							(font
								(size 1.27 1.27)
							)
						)
					)
				)
				(pin bidirectional line
					(at 0 -17.78 0)
					(length 5.08)
					(name "MGTXTXN3_115"
						(effects
							(font
								(size 1.27 1.27)
							)
						)
					)
					(number "A3"
						(effects
							(font
								(size 1.27 1.27)
							)
						)
					)
				)
				(pin bidirectional line
					(at 0 -22.86 0)
					(length 5.08)
					(name "MGTXRXP0_115"
						(effects
							(font
								(size 1.27 1.27)
							)
						)
					)
					(number "G4"
						(effects
							(font
								(size 1.27 1.27)
							)
						)
					)
				)
				(pin bidirectional line
					(at 0 -25.4 0)
					(length 5.08)
					(name "MGTXRXN0_115"
						(effects
							(font
								(size 1.27 1.27)
							)
						)
					)
					(number "G3"
						(effects
							(font
								(size 1.27 1.27)
							)
						)
					)
				)
				(pin bidirectional line
					(at 0 -27.94 0)
					(length 5.08)
					(name "MGTXRXP1_115"
						(effects
							(font
								(size 1.27 1.27)
							)
						)
					)
					(number "E4"
						(effects
							(font
								(size 1.27 1.27)
							)
						)
					)
				)
				(pin bidirectional line
					(at 0 -30.48 0)
					(length 5.08)
					(name "MGTXRXN1_115"
						(effects
							(font
								(size 1.27 1.27)
							)
						)
					)
					(number "E3"
						(effects
							(font
								(size 1.27 1.27)
							)
						)
					)
				)
				(pin bidirectional line
					(at 0 -33.02 0)
					(length 5.08)
					(name "MGTXRXP2_115"
						(effects
							(font
								(size 1.27 1.27)
							)
						)
					)
					(number "C4"
						(effects
							(font
								(size 1.27 1.27)
							)
						)
					)
				)
				(pin bidirectional line
					(at 0 -35.56 0)
					(length 5.08)
					(name "MGTXRXN2_115"
						(effects
							(font
								(size 1.27 1.27)
							)
						)
					)
					(number "C3"
						(effects
							(font
								(size 1.27 1.27)
							)
						)
					)
				)
				(pin bidirectional line
					(at 0 -38.1 0)
					(length 5.08)
					(name "MGTXRXP3_115"
						(effects
							(font
								(size 1.27 1.27)
							)
						)
					)
					(number "B6"
						(effects
							(font
								(size 1.27 1.27)
							)
						)
					)
				)
				(pin bidirectional line
					(at 0 -40.64 0)
					(length 5.08)
					(name "MGTXRXN3_115"
						(effects
							(font
								(size 1.27 1.27)
							)
						)
					)
					(number "B5"
						(effects
							(font
								(size 1.27 1.27)
							)
						)
					)
				)
				(pin bidirectional line
					(at 0 -45.72 0)
					(length 5.08)
					(name "MGTREFCLK0P_115"
						(effects
							(font
								(size 1.27 1.27)
							)
						)
					)
					(number "D6"
						(effects
							(font
								(size 1.27 1.27)
							)
						)
					)
				)
				(pin bidirectional line
					(at 0 -48.26 0)
					(length 5.08)
					(name "MGTREFCLK0N_115"
						(effects
							(font
								(size 1.27 1.27)
							)
						)
					)
					(number "D5"
						(effects
							(font
								(size 1.27 1.27)
							)
						)
					)
				)
				(pin bidirectional line
					(at 0 -50.8 0)
					(length 5.08)
					(name "MGTREFCLK1P_115"
						(effects
							(font
								(size 1.27 1.27)
							)
						)
					)
					(number "F6"
						(effects
							(font
								(size 1.27 1.27)
							)
						)
					)
				)
				(pin bidirectional line
					(at 0 -53.34 0)
					(length 5.08)
					(name "MGTREFCLK1N_115"
						(effects
							(font
								(size 1.27 1.27)
							)
						)
					)
					(number "F5"
						(effects
							(font
								(size 1.27 1.27)
							)
						)
					)
				)
			)
			(symbol "XC7K70T-FBG484_4_1"
				(rectangle
					(start 5.08 5.08)
					(end 39.37 -127)
					(stroke
						(width 0.254)
						(type default)
					)
					(fill
						(type background)
					)
				)
				(text "BANK34"
					(at 17.78 2.54 0)
					(effects
						(font
							(size 1.27 1.27)
							(thickness 0.15)
						)
						(justify left bottom)
					)
				)
				(pin bidirectional line
					(at 0 0 0)
					(length 5.08)
					(name "IO_0_VRN_34"
						(effects
							(font
								(size 1.27 1.27)
							)
						)
					)
					(number "K4"
						(effects
							(font
								(size 1.27 1.27)
							)
						)
					)
				)
				(pin bidirectional line
					(at 0 -2.54 0)
					(length 5.08)
					(name "IO_L1P_T0_34"
						(effects
							(font
								(size 1.27 1.27)
							)
						)
					)
					(number "L3"
						(effects
							(font
								(size 1.27 1.27)
							)
						)
					)
				)
				(pin bidirectional line
					(at 0 -5.08 0)
					(length 5.08)
					(name "IO_L1N_T0_34"
						(effects
							(font
								(size 1.27 1.27)
							)
						)
					)
					(number "M3"
						(effects
							(font
								(size 1.27 1.27)
							)
						)
					)
				)
				(pin bidirectional line
					(at 0 -7.62 0)
					(length 5.08)
					(name "IO_L2P_T0_34"
						(effects
							(font
								(size 1.27 1.27)
							)
						)
					)
					(number "K1"
						(effects
							(font
								(size 1.27 1.27)
							)
						)
					)
				)
				(pin bidirectional line
					(at 0 -10.16 0)
					(length 5.08)
					(name "IO_L2N_T0_34"
						(effects
							(font
								(size 1.27 1.27)
							)
						)
					)
					(number "L1"
						(effects
							(font
								(size 1.27 1.27)
							)
						)
					)
				)
				(pin bidirectional line
					(at 0 -12.7 0)
					(length 5.08)
					(name "IO_L3P_T0_DQS_34"
						(effects
							(font
								(size 1.27 1.27)
							)
						)
					)
					(number "M2"
						(effects
							(font
								(size 1.27 1.27)
							)
						)
					)
				)
				(pin bidirectional line
					(at 0 -15.24 0)
					(length 5.08)
					(name "IO_L3N_T0_DQS_34"
						(effects
							(font
								(size 1.27 1.27)
							)
						)
					)
					(number "M1"
						(effects
							(font
								(size 1.27 1.27)
							)
						)
					)
				)
				(pin bidirectional line
					(at 0 -17.78 0)
					(length 5.08)
					(name "IO_L4P_T0_34"
						(effects
							(font
								(size 1.27 1.27)
							)
						)
					)
					(number "K3"
						(effects
							(font
								(size 1.27 1.27)
							)
						)
					)
				)
				(pin bidirectional line
					(at 0 -20.32 0)
					(length 5.08)
					(name "IO_L4N_T0_34"
						(effects
							(font
								(size 1.27 1.27)
							)
						)
					)
					(number "K2"
						(effects
							(font
								(size 1.27 1.27)
							)
						)
					)
				)
				(pin bidirectional line
					(at 0 -22.86 0)
					(length 5.08)
					(name "IO_L5P_T0_34"
						(effects
							(font
								(size 1.27 1.27)
							)
						)
					)
					(number "N3"
						(effects
							(font
								(size 1.27 1.27)
							)
						)
					)
				)
				(pin bidirectional line
					(at 0 -25.4 0)
					(length 5.08)
					(name "IO_L5N_T0_34"
						(effects
							(font
								(size 1.27 1.27)
							)
						)
					)
					(number "N2"
						(effects
							(font
								(size 1.27 1.27)
							)
						)
					)
				)
				(pin bidirectional line
					(at 0 -27.94 0)
					(length 5.08)
					(name "IO_L6P_T0_34"
						(effects
							(font
								(size 1.27 1.27)
							)
						)
					)
					(number "L5"
						(effects
							(font
								(size 1.27 1.27)
							)
						)
					)
				)
				(pin bidirectional line
					(at 0 -30.48 0)
					(length 5.08)
					(name "IO_L6N_T0_VREF_34"
						(effects
							(font
								(size 1.27 1.27)
							)
						)
					)
					(number "L4"
						(effects
							(font
								(size 1.27 1.27)
							)
						)
					)
				)
				(pin bidirectional line
					(at 0 -33.02 0)
					(length 5.08)
					(name "IO_L7P_T1_34"
						(effects
							(font
								(size 1.27 1.27)
							)
						)
					)
					(number "P2"
						(effects
							(font
								(size 1.27 1.27)
							)
						)
					)
				)
				(pin bidirectional line
					(at 0 -35.56 0)
					(length 5.08)
					(name "IO_L7N_T1_34"
						(effects
							(font
								(size 1.27 1.27)
							)
						)
					)
					(number "R2"
						(effects
							(font
								(size 1.27 1.27)
							)
						)
					)
				)
				(pin bidirectional line
					(at 0 -38.1 0)
					(length 5.08)
					(name "IO_L8P_T1_34"
						(effects
							(font
								(size 1.27 1.27)
							)
						)
					)
					(number "P1"
						(effects
							(font
								(size 1.27 1.27)
							)
						)
					)
				)
				(pin bidirectional line
					(at 0 -40.64 0)
					(length 5.08)
					(name "IO_L8N_T1_34"
						(effects
							(font
								(size 1.27 1.27)
							)
						)
					)
					(number "R1"
						(effects
							(font
								(size 1.27 1.27)
							)
						)
					)
				)
				(pin bidirectional line
					(at 0 -43.18 0)
					(length 5.08)
					(name "IO_L9P_T1_DQS_34"
						(effects
							(font
								(size 1.27 1.27)
							)
						)
					)
					(number "M5"
						(effects
							(font
								(size 1.27 1.27)
							)
						)
					)
				)
				(pin bidirectional line
					(at 0 -45.72 0)
					(length 5.08)
					(name "IO_L9N_T1_DQS_34"
						(effects
							(font
								(size 1.27 1.27)
							)
						)
					)
					(number "N4"
						(effects
							(font
								(size 1.27 1.27)
							)
						)
					)
				)
				(pin bidirectional line
					(at 0 -48.26 0)
					(length 5.08)
					(name "IO_L10P_T1_34"
						(effects
							(font
								(size 1.27 1.27)
							)
						)
					)
					(number "T1"
						(effects
							(font
								(size 1.27 1.27)
							)
						)
					)
				)
				(pin bidirectional line
					(at 0 -50.8 0)
					(length 5.08)
					(name "IO_L10N_T1_34"
						(effects
							(font
								(size 1.27 1.27)
							)
						)
					)
					(number "U1"
						(effects
							(font
								(size 1.27 1.27)
							)
						)
					)
				)
				(pin bidirectional line
					(at 0 -53.34 0)
					(length 5.08)
					(name "IO_L11P_T1_SRCC_34"
						(effects
							(font
								(size 1.27 1.27)
							)
						)
					)
					(number "P4"
						(effects
							(font
								(size 1.27 1.27)
							)
						)
					)
				)
				(pin bidirectional line
					(at 0 -55.88 0)
					(length 5.08)
					(name "IO_L11N_T1_SRCC_34"
						(effects
							(font
								(size 1.27 1.27)
							)
						)
					)
					(number "R4"
						(effects
							(font
								(size 1.27 1.27)
							)
						)
					)
				)
				(pin bidirectional line
					(at 0 -58.42 0)
					(length 5.08)
					(name "IO_L12P_T1_MRCC_34"
						(effects
							(font
								(size 1.27 1.27)
							)
						)
					)
					(number "R3"
						(effects
							(font
								(size 1.27 1.27)
							)
						)
					)
				)
				(pin bidirectional line
					(at 0 -60.96 0)
					(length 5.08)
					(name "IO_L12N_T1_MRCC_34"
						(effects
							(font
								(size 1.27 1.27)
							)
						)
					)
					(number "T3"
						(effects
							(font
								(size 1.27 1.27)
							)
						)
					)
				)
				(pin bidirectional line
					(at 0 -63.5 0)
					(length 5.08)
					(name "IO_L13P_T2_MRCC_34"
						(effects
							(font
								(size 1.27 1.27)
							)
						)
					)
					(number "T4"
						(effects
							(font
								(size 1.27 1.27)
							)
						)
					)
				)
				(pin bidirectional line
					(at 0 -66.04 0)
					(length 5.08)
					(name "IO_L13N_T2_MRCC_34"
						(effects
							(font
								(size 1.27 1.27)
							)
						)
					)
					(number "U3"
						(effects
							(font
								(size 1.27 1.27)
							)
						)
					)
				)
				(pin bidirectional line
					(at 0 -68.58 0)
					(length 5.08)
					(name "IO_L14P_T2_SRCC_34"
						(effects
							(font
								(size 1.27 1.27)
							)
						)
					)
					(number "V4"
						(effects
							(font
								(size 1.27 1.27)
							)
						)
					)
				)
				(pin bidirectional line
					(at 0 -71.12 0)
					(length 5.08)
					(name "IO_L14N_T2_SRCC_34"
						(effects
							(font
								(size 1.27 1.27)
							)
						)
					)
					(number "W4"
						(effects
							(font
								(size 1.27 1.27)
							)
						)
					)
				)
				(pin bidirectional line
					(at 0 -73.66 0)
					(length 5.08)
					(name "IO_L15P_T2_DQS_34"
						(effects
							(font
								(size 1.27 1.27)
							)
						)
					)
					(number "U2"
						(effects
							(font
								(size 1.27 1.27)
							)
						)
					)
				)
				(pin bidirectional line
					(at 0 -76.2 0)
					(length 5.08)
					(name "IO_L15N_T2_DQS_34"
						(effects
							(font
								(size 1.27 1.27)
							)
						)
					)
					(number "V2"
						(effects
							(font
								(size 1.27 1.27)
							)
						)
					)
				)
				(pin bidirectional line
					(at 0 -78.74 0)
					(length 5.08)
					(name "IO_L16P_T2_34"
						(effects
							(font
								(size 1.27 1.27)
							)
						)
					)
					(number "T5"
						(effects
							(font
								(size 1.27 1.27)
							)
						)
					)
				)
				(pin bidirectional line
					(at 0 -81.28 0)
					(length 5.08)
					(name "IO_L16N_T2_34"
						(effects
							(font
								(size 1.27 1.27)
							)
						)
					)
					(number "U5"
						(effects
							(font
								(size 1.27 1.27)
							)
						)
					)
				)
				(pin bidirectional line
					(at 0 -83.82 0)
					(length 5.08)
					(name "IO_L17P_T2_34"
						(effects
							(font
								(size 1.27 1.27)
							)
						)
					)
					(number "V3"
						(effects
							(font
								(size 1.27 1.27)
							)
						)
					)
				)
				(pin bidirectional line
					(at 0 -86.36 0)
					(length 5.08)
					(name "IO_L17N_T2_34"
						(effects
							(font
								(size 1.27 1.27)
							)
						)
					)
					(number "W2"
						(effects
							(font
								(size 1.27 1.27)
							)
						)
					)
				)
				(pin bidirectional line
					(at 0 -88.9 0)
					(length 5.08)
					(name "IO_L18P_T2_34"
						(effects
							(font
								(size 1.27 1.27)
							)
						)
					)
					(number "N5"
						(effects
							(font
								(size 1.27 1.27)
							)
						)
					)
				)
				(pin bidirectional line
					(at 0 -91.44 0)
					(length 5.08)
					(name "IO_L18N_T2_34"
						(effects
							(font
								(size 1.27 1.27)
							)
						)
					)
					(number "P5"
						(effects
							(font
								(size 1.27 1.27)
							)
						)
					)
				)
				(pin bidirectional line
					(at 0 -93.98 0)
					(length 5.08)
					(name "IO_L19P_T3_34"
						(effects
							(font
								(size 1.27 1.27)
							)
						)
					)
					(number "W5"
						(effects
							(font
								(size 1.27 1.27)
							)
						)
					)
				)
				(pin bidirectional line
					(at 0 -96.52 0)
					(length 5.08)
					(name "IO_L19N_T3_VREF_34"
						(effects
							(font
								(size 1.27 1.27)
							)
						)
					)
					(number "Y4"
						(effects
							(font
								(size 1.27 1.27)
							)
						)
					)
				)
				(pin bidirectional line
					(at 0 -99.06 0)
					(length 5.08)
					(name "IO_L20P_T3_34"
						(effects
							(font
								(size 1.27 1.27)
							)
						)
					)
					(number "W1"
						(effects
							(font
								(size 1.27 1.27)
							)
						)
					)
				)
				(pin bidirectional line
					(at 0 -101.6 0)
					(length 5.08)
					(name "IO_L20N_T3_34"
						(effects
							(font
								(size 1.27 1.27)
							)
						)
					)
					(number "Y1"
						(effects
							(font
								(size 1.27 1.27)
							)
						)
					)
				)
				(pin bidirectional line
					(at 0 -104.14 0)
					(length 5.08)
					(name "IO_L21P_T3_DQS_34"
						(effects
							(font
								(size 1.27 1.27)
							)
						)
					)
					(number "Y3"
						(effects
							(font
								(size 1.27 1.27)
							)
						)
					)
				)
				(pin bidirectional line
					(at 0 -106.68 0)
					(length 5.08)
					(name "IO_L21N_T3_DQS_34"
						(effects
							(font
								(size 1.27 1.27)
							)
						)
					)
					(number "Y2"
						(effects
							(font
								(size 1.27 1.27)
							)
						)
					)
				)
				(pin bidirectional line
					(at 0 -109.22 0)
					(length 5.08)
					(name "IO_L22P_T3_34"
						(effects
							(font
								(size 1.27 1.27)
							)
						)
					)
					(number "AA1"
						(effects
							(font
								(size 1.27 1.27)
							)
						)
					)
				)
				(pin bidirectional line
					(at 0 -111.76 0)
					(length 5.08)
					(name "IO_L22N_T3_34"
						(effects
							(font
								(size 1.27 1.27)
							)
						)
					)
					(number "AB1"
						(effects
							(font
								(size 1.27 1.27)
							)
						)
					)
				)
				(pin bidirectional line
					(at 0 -114.3 0)
					(length 5.08)
					(name "IO_L23P_T3_34"
						(effects
							(font
								(size 1.27 1.27)
							)
						)
					)
					(number "AA3"
						(effects
							(font
								(size 1.27 1.27)
							)
						)
					)
				)
				(pin bidirectional line
					(at 0 -116.84 0)
					(length 5.08)
					(name "IO_L23N_T3_34"
						(effects
							(font
								(size 1.27 1.27)
							)
						)
					)
					(number "AB2"
						(effects
							(font
								(size 1.27 1.27)
							)
						)
					)
				)
				(pin bidirectional line
					(at 0 -119.38 0)
					(length 5.08)
					(name "IO_L24P_T3_34"
						(effects
							(font
								(size 1.27 1.27)
							)
						)
					)
					(number "AA4"
						(effects
							(font
								(size 1.27 1.27)
							)
						)
					)
				)
				(pin bidirectional line
					(at 0 -121.92 0)
					(length 5.08)
					(name "IO_L24N_T3_34"
						(effects
							(font
								(size 1.27 1.27)
							)
						)
					)
					(number "AB3"
						(effects
							(font
								(size 1.27 1.27)
							)
						)
					)
				)
				(pin bidirectional line
					(at 0 -124.46 0)
					(length 5.08)
					(name "IO_25_VRP_34"
						(effects
							(font
								(size 1.27 1.27)
							)
						)
					)
					(number "V5"
						(effects
							(font
								(size 1.27 1.27)
							)
						)
					)
				)
			)
			(symbol "XC7K70T-FBG484_5_1"
				(rectangle
					(start 5.08 5.08)
					(end 39.37 -127)
					(stroke
						(width 0.254)
						(type default)
					)
					(fill
						(type background)
					)
				)
				(text "BANK33"
					(at 17.78 2.54 0)
					(effects
						(font
							(size 1.27 1.27)
							(thickness 0.15)
						)
						(justify left bottom)
					)
				)
				(pin bidirectional line
					(at 0 0 0)
					(length 5.08)
					(name "IO_0_VRN_33"
						(effects
							(font
								(size 1.27 1.27)
							)
						)
					)
					(number "T6"
						(effects
							(font
								(size 1.27 1.27)
							)
						)
					)
				)
				(pin bidirectional line
					(at 0 -2.54 0)
					(length 5.08)
					(name "IO_L1P_T0_33"
						(effects
							(font
								(size 1.27 1.27)
							)
						)
					)
					(number "AA5"
						(effects
							(font
								(size 1.27 1.27)
							)
						)
					)
				)
				(pin bidirectional line
					(at 0 -5.08 0)
					(length 5.08)
					(name "IO_L1N_T0_33"
						(effects
							(font
								(size 1.27 1.27)
							)
						)
					)
					(number "AB5"
						(effects
							(font
								(size 1.27 1.27)
							)
						)
					)
				)
				(pin bidirectional line
					(at 0 -7.62 0)
					(length 5.08)
					(name "IO_L2P_T0_33"
						(effects
							(font
								(size 1.27 1.27)
							)
						)
					)
					(number "AB8"
						(effects
							(font
								(size 1.27 1.27)
							)
						)
					)
				)
				(pin bidirectional line
					(at 0 -10.16 0)
					(length 5.08)
					(name "IO_L2N_T0_33"
						(effects
							(font
								(size 1.27 1.27)
							)
						)
					)
					(number "AB7"
						(effects
							(font
								(size 1.27 1.27)
							)
						)
					)
				)
				(pin bidirectional line
					(at 0 -12.7 0)
					(length 5.08)
					(name "IO_L3P_T0_DQS_33"
						(effects
							(font
								(size 1.27 1.27)
							)
						)
					)
					(number "AA6"
						(effects
							(font
								(size 1.27 1.27)
							)
						)
					)
				)
				(pin bidirectional line
					(at 0 -15.24 0)
					(length 5.08)
					(name "IO_L3N_T0_DQS_33"
						(effects
							(font
								(size 1.27 1.27)
							)
						)
					)
					(number "AB6"
						(effects
							(font
								(size 1.27 1.27)
							)
						)
					)
				)
				(pin bidirectional line
					(at 0 -17.78 0)
					(length 5.08)
					(name "IO_L4P_T0_33"
						(effects
							(font
								(size 1.27 1.27)
							)
						)
					)
					(number "AA10"
						(effects
							(font
								(size 1.27 1.27)
							)
						)
					)
				)
				(pin bidirectional line
					(at 0 -20.32 0)
					(length 5.08)
					(name "IO_L4N_T0_33"
						(effects
							(font
								(size 1.27 1.27)
							)
						)
					)
					(number "AB10"
						(effects
							(font
								(size 1.27 1.27)
							)
						)
					)
				)
				(pin bidirectional line
					(at 0 -22.86 0)
					(length 5.08)
					(name "IO_L5P_T0_33"
						(effects
							(font
								(size 1.27 1.27)
							)
						)
					)
					(number "AA9"
						(effects
							(font
								(size 1.27 1.27)
							)
						)
					)
				)
				(pin bidirectional line
					(at 0 -25.4 0)
					(length 5.08)
					(name "IO_L5N_T0_33"
						(effects
							(font
								(size 1.27 1.27)
							)
						)
					)
					(number "AA8"
						(effects
							(font
								(size 1.27 1.27)
							)
						)
					)
				)
				(pin bidirectional line
					(at 0 -27.94 0)
					(length 5.08)
					(name "IO_L6P_T0_33"
						(effects
							(font
								(size 1.27 1.27)
							)
						)
					)
					(number "W11"
						(effects
							(font
								(size 1.27 1.27)
							)
						)
					)
				)
				(pin bidirectional line
					(at 0 -30.48 0)
					(length 5.08)
					(name "IO_L6N_T0_VREF_33"
						(effects
							(font
								(size 1.27 1.27)
							)
						)
					)
					(number "Y11"
						(effects
							(font
								(size 1.27 1.27)
							)
						)
					)
				)
				(pin bidirectional line
					(at 0 -33.02 0)
					(length 5.08)
					(name "IO_L7P_T1_33"
						(effects
							(font
								(size 1.27 1.27)
							)
						)
					)
					(number "W6"
						(effects
							(font
								(size 1.27 1.27)
							)
						)
					)
				)
				(pin bidirectional line
					(at 0 -35.56 0)
					(length 5.08)
					(name "IO_L7N_T1_33"
						(effects
							(font
								(size 1.27 1.27)
							)
						)
					)
					(number "Y6"
						(effects
							(font
								(size 1.27 1.27)
							)
						)
					)
				)
				(pin bidirectional line
					(at 0 -38.1 0)
					(length 5.08)
					(name "IO_L8P_T1_33"
						(effects
							(font
								(size 1.27 1.27)
							)
						)
					)
					(number "R7"
						(effects
							(font
								(size 1.27 1.27)
							)
						)
					)
				)
				(pin bidirectional line
					(at 0 -40.64 0)
					(length 5.08)
					(name "IO_L8N_T1_33"
						(effects
							(font
								(size 1.27 1.27)
							)
						)
					)
					(number "R6"
						(effects
							(font
								(size 1.27 1.27)
							)
						)
					)
				)
				(pin bidirectional line
					(at 0 -43.18 0)
					(length 5.08)
					(name "IO_L9P_T1_DQS_33"
						(effects
							(font
								(size 1.27 1.27)
							)
						)
					)
					(number "U8"
						(effects
							(font
								(size 1.27 1.27)
							)
						)
					)
				)
				(pin bidirectional line
					(at 0 -45.72 0)
					(length 5.08)
					(name "IO_L9N_T1_DQS_33"
						(effects
							(font
								(size 1.27 1.27)
							)
						)
					)
					(number "V8"
						(effects
							(font
								(size 1.27 1.27)
							)
						)
					)
				)
				(pin bidirectional line
					(at 0 -48.26 0)
					(length 5.08)
					(name "IO_L10P_T1_33"
						(effects
							(font
								(size 1.27 1.27)
							)
						)
					)
					(number "U7"
						(effects
							(font
								(size 1.27 1.27)
							)
						)
					)
				)
				(pin bidirectional line
					(at 0 -50.8 0)
					(length 5.08)
					(name "IO_L10N_T1_33"
						(effects
							(font
								(size 1.27 1.27)
							)
						)
					)
					(number "U6"
						(effects
							(font
								(size 1.27 1.27)
							)
						)
					)
				)
				(pin bidirectional line
					(at 0 -53.34 0)
					(length 5.08)
					(name "IO_L11P_T1_SRCC_33"
						(effects
							(font
								(size 1.27 1.27)
							)
						)
					)
					(number "V7"
						(effects
							(font
								(size 1.27 1.27)
							)
						)
					)
				)
				(pin bidirectional line
					(at 0 -55.88 0)
					(length 5.08)
					(name "IO_L11N_T1_SRCC_33"
						(effects
							(font
								(size 1.27 1.27)
							)
						)
					)
					(number "W7"
						(effects
							(font
								(size 1.27 1.27)
							)
						)
					)
				)
				(pin bidirectional line
					(at 0 -58.42 0)
					(length 5.08)
					(name "IO_L12P_T1_MRCC_33"
						(effects
							(font
								(size 1.27 1.27)
							)
						)
					)
					(number "Y8"
						(effects
							(font
								(size 1.27 1.27)
							)
						)
					)
				)
				(pin bidirectional line
					(at 0 -60.96 0)
					(length 5.08)
					(name "IO_L12N_T1_MRCC_33"
						(effects
							(font
								(size 1.27 1.27)
							)
						)
					)
					(number "Y7"
						(effects
							(font
								(size 1.27 1.27)
							)
						)
					)
				)
				(pin bidirectional line
					(at 0 -63.5 0)
					(length 5.08)
					(name "IO_L13P_T2_MRCC_33"
						(effects
							(font
								(size 1.27 1.27)
							)
						)
					)
					(number "W9"
						(effects
							(font
								(size 1.27 1.27)
							)
						)
					)
				)
				(pin bidirectional line
					(at 0 -66.04 0)
					(length 5.08)
					(name "IO_L13N_T2_MRCC_33"
						(effects
							(font
								(size 1.27 1.27)
							)
						)
					)
					(number "Y9"
						(effects
							(font
								(size 1.27 1.27)
							)
						)
					)
				)
				(pin bidirectional line
					(at 0 -68.58 0)
					(length 5.08)
					(name "IO_L14P_T2_SRCC_33"
						(effects
							(font
								(size 1.27 1.27)
							)
						)
					)
					(number "U10"
						(effects
							(font
								(size 1.27 1.27)
							)
						)
					)
				)
				(pin bidirectional line
					(at 0 -71.12 0)
					(length 5.08)
					(name "IO_L14N_T2_SRCC_33"
						(effects
							(font
								(size 1.27 1.27)
							)
						)
					)
					(number "V9"
						(effects
							(font
								(size 1.27 1.27)
							)
						)
					)
				)
				(pin bidirectional line
					(at 0 -73.66 0)
					(length 5.08)
					(name "IO_L15P_T2_DQS_33"
						(effects
							(font
								(size 1.27 1.27)
							)
						)
					)
					(number "V10"
						(effects
							(font
								(size 1.27 1.27)
							)
						)
					)
				)
				(pin bidirectional line
					(at 0 -76.2 0)
					(length 5.08)
					(name "IO_L15N_T2_DQS_33"
						(effects
							(font
								(size 1.27 1.27)
							)
						)
					)
					(number "W10"
						(effects
							(font
								(size 1.27 1.27)
							)
						)
					)
				)
				(pin bidirectional line
					(at 0 -78.74 0)
					(length 5.08)
					(name "IO_L16P_T2_33"
						(effects
							(font
								(size 1.27 1.27)
							)
						)
					)
					(number "T11"
						(effects
							(font
								(size 1.27 1.27)
							)
						)
					)
				)
				(pin bidirectional line
					(at 0 -81.28 0)
					(length 5.08)
					(name "IO_L16N_T2_33"
						(effects
							(font
								(size 1.27 1.27)
							)
						)
					)
					(number "T10"
						(effects
							(font
								(size 1.27 1.27)
							)
						)
					)
				)
				(pin bidirectional line
					(at 0 -83.82 0)
					(length 5.08)
					(name "IO_L17P_T2_33"
						(effects
							(font
								(size 1.27 1.27)
							)
						)
					)
					(number "U12"
						(effects
							(font
								(size 1.27 1.27)
							)
						)
					)
				)
				(pin bidirectional line
					(at 0 -86.36 0)
					(length 5.08)
					(name "IO_L17N_T2_33"
						(effects
							(font
								(size 1.27 1.27)
							)
						)
					)
					(number "U11"
						(effects
							(font
								(size 1.27 1.27)
							)
						)
					)
				)
				(pin bidirectional line
					(at 0 -88.9 0)
					(length 5.08)
					(name "IO_L18P_T2_33"
						(effects
							(font
								(size 1.27 1.27)
							)
						)
					)
					(number "T9"
						(effects
							(font
								(size 1.27 1.27)
							)
						)
					)
				)
				(pin bidirectional line
					(at 0 -91.44 0)
					(length 5.08)
					(name "IO_L18N_T2_33"
						(effects
							(font
								(size 1.27 1.27)
							)
						)
					)
					(number "T8"
						(effects
							(font
								(size 1.27 1.27)
							)
						)
					)
				)
				(pin bidirectional line
					(at 0 -93.98 0)
					(length 5.08)
					(name "IO_L19P_T3_33"
						(effects
							(font
								(size 1.27 1.27)
							)
						)
					)
					(number "W12"
						(effects
							(font
								(size 1.27 1.27)
							)
						)
					)
				)
				(pin bidirectional line
					(at 0 -96.52 0)
					(length 5.08)
					(name "IO_L19N_T3_VREF_33"
						(effects
							(font
								(size 1.27 1.27)
							)
						)
					)
					(number "Y12"
						(effects
							(font
								(size 1.27 1.27)
							)
						)
					)
				)
				(pin bidirectional line
					(at 0 -99.06 0)
					(length 5.08)
					(name "IO_L20P_T3_33"
						(effects
							(font
								(size 1.27 1.27)
							)
						)
					)
					(number "AA11"
						(effects
							(font
								(size 1.27 1.27)
							)
						)
					)
				)
				(pin bidirectional line
					(at 0 -101.6 0)
					(length 5.08)
					(name "IO_L20N_T3_33"
						(effects
							(font
								(size 1.27 1.27)
							)
						)
					)
					(number "AB11"
						(effects
							(font
								(size 1.27 1.27)
							)
						)
					)
				)
				(pin bidirectional line
					(at 0 -104.14 0)
					(length 5.08)
					(name "IO_L21P_T3_DQS_33"
						(effects
							(font
								(size 1.27 1.27)
							)
						)
					)
					(number "Y13"
						(effects
							(font
								(size 1.27 1.27)
							)
						)
					)
				)
				(pin bidirectional line
					(at 0 -106.68 0)
					(length 5.08)
					(name "IO_L21N_T3_DQS_33"
						(effects
							(font
								(size 1.27 1.27)
							)
						)
					)
					(number "AA13"
						(effects
							(font
								(size 1.27 1.27)
							)
						)
					)
				)
				(pin bidirectional line
					(at 0 -109.22 0)
					(length 5.08)
					(name "IO_L22P_T3_33"
						(effects
							(font
								(size 1.27 1.27)
							)
						)
					)
					(number "AB13"
						(effects
							(font
								(size 1.27 1.27)
							)
						)
					)
				)
				(pin bidirectional line
					(at 0 -111.76 0)
					(length 5.08)
					(name "IO_L22N_T3_33"
						(effects
							(font
								(size 1.27 1.27)
							)
						)
					)
					(number "AB12"
						(effects
							(font
								(size 1.27 1.27)
							)
						)
					)
				)
				(pin bidirectional line
					(at 0 -114.3 0)
					(length 5.08)
					(name "IO_L23P_T3_33"
						(effects
							(font
								(size 1.27 1.27)
							)
						)
					)
					(number "V13"
						(effects
							(font
								(size 1.27 1.27)
							)
						)
					)
				)
				(pin bidirectional line
					(at 0 -116.84 0)
					(length 5.08)
					(name "IO_L23N_T3_33"
						(effects
							(font
								(size 1.27 1.27)
							)
						)
					)
					(number "V12"
						(effects
							(font
								(size 1.27 1.27)
							)
						)
					)
				)
				(pin bidirectional line
					(at 0 -119.38 0)
					(length 5.08)
					(name "IO_L24P_T3_33"
						(effects
							(font
								(size 1.27 1.27)
							)
						)
					)
					(number "T13"
						(effects
							(font
								(size 1.27 1.27)
							)
						)
					)
				)
				(pin bidirectional line
					(at 0 -121.92 0)
					(length 5.08)
					(name "IO_L24N_T3_33"
						(effects
							(font
								(size 1.27 1.27)
							)
						)
					)
					(number "U13"
						(effects
							(font
								(size 1.27 1.27)
							)
						)
					)
				)
				(pin bidirectional line
					(at 0 -124.46 0)
					(length 5.08)
					(name "IO_25_VRP_33"
						(effects
							(font
								(size 1.27 1.27)
							)
						)
					)
					(number "T14"
						(effects
							(font
								(size 1.27 1.27)
							)
						)
					)
				)
			)
			(symbol "XC7K70T-FBG484_6_1"
				(rectangle
					(start 5.08 5.08)
					(end 39.37 -88.9)
					(stroke
						(width 0.254)
						(type default)
					)
					(fill
						(type background)
					)
				)
				(text "BANK16"
					(at 17.78 2.54 0)
					(effects
						(font
							(size 1.27 1.27)
							(thickness 0.15)
						)
						(justify left bottom)
					)
				)
				(pin bidirectional line
					(at 0 0 0)
					(length 5.08)
					(name "IO_6_T0_VREF_16"
						(effects
							(font
								(size 1.27 1.27)
							)
						)
					)
					(number "F14"
						(effects
							(font
								(size 1.27 1.27)
							)
						)
					)
				)
				(pin bidirectional line
					(at 0 -2.54 0)
					(length 5.08)
					(name "IO_L7P_T1_16"
						(effects
							(font
								(size 1.27 1.27)
							)
						)
					)
					(number "D10"
						(effects
							(font
								(size 1.27 1.27)
							)
						)
					)
				)
				(pin bidirectional line
					(at 0 -5.08 0)
					(length 5.08)
					(name "IO_L7N_T1_16"
						(effects
							(font
								(size 1.27 1.27)
							)
						)
					)
					(number "C10"
						(effects
							(font
								(size 1.27 1.27)
							)
						)
					)
				)
				(pin bidirectional line
					(at 0 -7.62 0)
					(length 5.08)
					(name "IO_L8P_T1_16"
						(effects
							(font
								(size 1.27 1.27)
							)
						)
					)
					(number "G13"
						(effects
							(font
								(size 1.27 1.27)
							)
						)
					)
				)
				(pin bidirectional line
					(at 0 -10.16 0)
					(length 5.08)
					(name "IO_L8N_T1_16"
						(effects
							(font
								(size 1.27 1.27)
							)
						)
					)
					(number "F13"
						(effects
							(font
								(size 1.27 1.27)
							)
						)
					)
				)
				(pin bidirectional line
					(at 0 -12.7 0)
					(length 5.08)
					(name "IO_L9P_T1_DQS_16"
						(effects
							(font
								(size 1.27 1.27)
							)
						)
					)
					(number "H14"
						(effects
							(font
								(size 1.27 1.27)
							)
						)
					)
				)
				(pin bidirectional line
					(at 0 -15.24 0)
					(length 5.08)
					(name "IO_L9N_T1_DQS_16"
						(effects
							(font
								(size 1.27 1.27)
							)
						)
					)
					(number "H13"
						(effects
							(font
								(size 1.27 1.27)
							)
						)
					)
				)
				(pin bidirectional line
					(at 0 -17.78 0)
					(length 5.08)
					(name "IO_L10P_T1_16"
						(effects
							(font
								(size 1.27 1.27)
							)
						)
					)
					(number "E13"
						(effects
							(font
								(size 1.27 1.27)
							)
						)
					)
				)
				(pin bidirectional line
					(at 0 -20.32 0)
					(length 5.08)
					(name "IO_L10N_T1_16"
						(effects
							(font
								(size 1.27 1.27)
							)
						)
					)
					(number "E12"
						(effects
							(font
								(size 1.27 1.27)
							)
						)
					)
				)
				(pin bidirectional line
					(at 0 -22.86 0)
					(length 5.08)
					(name "IO_L11P_T1_SRCC_16"
						(effects
							(font
								(size 1.27 1.27)
							)
						)
					)
					(number "F11"
						(effects
							(font
								(size 1.27 1.27)
							)
						)
					)
				)
				(pin bidirectional line
					(at 0 -25.4 0)
					(length 5.08)
					(name "IO_L11N_T1_SRCC_16"
						(effects
							(font
								(size 1.27 1.27)
							)
						)
					)
					(number "F10"
						(effects
							(font
								(size 1.27 1.27)
							)
						)
					)
				)
				(pin bidirectional line
					(at 0 -27.94 0)
					(length 5.08)
					(name "IO_L12P_T1_MRCC_16"
						(effects
							(font
								(size 1.27 1.27)
							)
						)
					)
					(number "E11"
						(effects
							(font
								(size 1.27 1.27)
							)
						)
					)
				)
				(pin bidirectional line
					(at 0 -30.48 0)
					(length 5.08)
					(name "IO_L12N_T1_MRCC_16"
						(effects
							(font
								(size 1.27 1.27)
							)
						)
					)
					(number "D11"
						(effects
							(font
								(size 1.27 1.27)
							)
						)
					)
				)
				(pin bidirectional line
					(at 0 -33.02 0)
					(length 5.08)
					(name "IO_L13P_T2_MRCC_16"
						(effects
							(font
								(size 1.27 1.27)
							)
						)
					)
					(number "G11"
						(effects
							(font
								(size 1.27 1.27)
							)
						)
					)
				)
				(pin bidirectional line
					(at 0 -35.56 0)
					(length 5.08)
					(name "IO_L13N_T2_MRCC_16"
						(effects
							(font
								(size 1.27 1.27)
							)
						)
					)
					(number "G10"
						(effects
							(font
								(size 1.27 1.27)
							)
						)
					)
				)
				(pin bidirectional line
					(at 0 -38.1 0)
					(length 5.08)
					(name "IO_L14P_T2_SRCC_16"
						(effects
							(font
								(size 1.27 1.27)
							)
						)
					)
					(number "H12"
						(effects
							(font
								(size 1.27 1.27)
							)
						)
					)
				)
				(pin bidirectional line
					(at 0 -40.64 0)
					(length 5.08)
					(name "IO_L14N_T2_SRCC_16"
						(effects
							(font
								(size 1.27 1.27)
							)
						)
					)
					(number "G12"
						(effects
							(font
								(size 1.27 1.27)
							)
						)
					)
				)
				(pin bidirectional line
					(at 0 -43.18 0)
					(length 5.08)
					(name "IO_L15P_T2_DQS_16"
						(effects
							(font
								(size 1.27 1.27)
							)
						)
					)
					(number "F9"
						(effects
							(font
								(size 1.27 1.27)
							)
						)
					)
				)
				(pin bidirectional line
					(at 0 -45.72 0)
					(length 5.08)
					(name "IO_L15N_T2_DQS_16"
						(effects
							(font
								(size 1.27 1.27)
							)
						)
					)
					(number "E9"
						(effects
							(font
								(size 1.27 1.27)
							)
						)
					)
				)
				(pin bidirectional line
					(at 0 -48.26 0)
					(length 5.08)
					(name "IO_L16P_T2_16"
						(effects
							(font
								(size 1.27 1.27)
							)
						)
					)
					(number "H9"
						(effects
							(font
								(size 1.27 1.27)
							)
						)
					)
				)
				(pin bidirectional line
					(at 0 -50.8 0)
					(length 5.08)
					(name "IO_L16N_T2_16"
						(effects
							(font
								(size 1.27 1.27)
							)
						)
					)
					(number "H8"
						(effects
							(font
								(size 1.27 1.27)
							)
						)
					)
				)
				(pin bidirectional line
					(at 0 -53.34 0)
					(length 5.08)
					(name "IO_L17P_T2_16"
						(effects
							(font
								(size 1.27 1.27)
							)
						)
					)
					(number "G8"
						(effects
							(font
								(size 1.27 1.27)
							)
						)
					)
				)
				(pin bidirectional line
					(at 0 -55.88 0)
					(length 5.08)
					(name "IO_L17N_T2_16"
						(effects
							(font
								(size 1.27 1.27)
							)
						)
					)
					(number "F8"
						(effects
							(font
								(size 1.27 1.27)
							)
						)
					)
				)
				(pin bidirectional line
					(at 0 -58.42 0)
					(length 5.08)
					(name "IO_18_T2_16"
						(effects
							(font
								(size 1.27 1.27)
							)
						)
					)
					(number "H10"
						(effects
							(font
								(size 1.27 1.27)
							)
						)
					)
				)
				(pin bidirectional line
					(at 0 -60.96 0)
					(length 5.08)
					(name "IO_L19P_T3_16"
						(effects
							(font
								(size 1.27 1.27)
							)
						)
					)
					(number "D9"
						(effects
							(font
								(size 1.27 1.27)
							)
						)
					)
				)
				(pin bidirectional line
					(at 0 -63.5 0)
					(length 5.08)
					(name "IO_L19N_T3_VREF_16"
						(effects
							(font
								(size 1.27 1.27)
							)
						)
					)
					(number "C9"
						(effects
							(font
								(size 1.27 1.27)
							)
						)
					)
				)
				(pin bidirectional line
					(at 0 -66.04 0)
					(length 5.08)
					(name "IO_L20P_T3_16"
						(effects
							(font
								(size 1.27 1.27)
							)
						)
					)
					(number "B11"
						(effects
							(font
								(size 1.27 1.27)
							)
						)
					)
				)
				(pin bidirectional line
					(at 0 -68.58 0)
					(length 5.08)
					(name "IO_L20N_T3_16"
						(effects
							(font
								(size 1.27 1.27)
							)
						)
					)
					(number "B10"
						(effects
							(font
								(size 1.27 1.27)
							)
						)
					)
				)
				(pin bidirectional line
					(at 0 -71.12 0)
					(length 5.08)
					(name "IO_L21P_T3_DQS_16"
						(effects
							(font
								(size 1.27 1.27)
							)
						)
					)
					(number "A9"
						(effects
							(font
								(size 1.27 1.27)
							)
						)
					)
				)
				(pin bidirectional line
					(at 0 -73.66 0)
					(length 5.08)
					(name "IO_L21N_T3_DQS_16"
						(effects
							(font
								(size 1.27 1.27)
							)
						)
					)
					(number "A8"
						(effects
							(font
								(size 1.27 1.27)
							)
						)
					)
				)
				(pin bidirectional line
					(at 0 -76.2 0)
					(length 5.08)
					(name "IO_L22P_T3_16"
						(effects
							(font
								(size 1.27 1.27)
							)
						)
					)
					(number "C8"
						(effects
							(font
								(size 1.27 1.27)
							)
						)
					)
				)
				(pin bidirectional line
					(at 0 -78.74 0)
					(length 5.08)
					(name "IO_L22N_T3_16"
						(effects
							(font
								(size 1.27 1.27)
							)
						)
					)
					(number "B8"
						(effects
							(font
								(size 1.27 1.27)
							)
						)
					)
				)
				(pin bidirectional line
					(at 0 -81.28 0)
					(length 5.08)
					(name "IO_L23P_T3_16"
						(effects
							(font
								(size 1.27 1.27)
							)
						)
					)
					(number "A11"
						(effects
							(font
								(size 1.27 1.27)
							)
						)
					)
				)
				(pin bidirectional line
					(at 0 -83.82 0)
					(length 5.08)
					(name "IO_L23N_T3_16"
						(effects
							(font
								(size 1.27 1.27)
							)
						)
					)
					(number "A10"
						(effects
							(font
								(size 1.27 1.27)
							)
						)
					)
				)
				(pin bidirectional line
					(at 0 -86.36 0)
					(length 5.08)
					(name "IO_24_T3_16"
						(effects
							(font
								(size 1.27 1.27)
							)
						)
					)
					(number "E8"
						(effects
							(font
								(size 1.27 1.27)
							)
						)
					)
				)
			)
			(symbol "XC7K70T-FBG484_7_1"
				(rectangle
					(start 5.08 5.08)
					(end 39.37 -127)
					(stroke
						(width 0.254)
						(type default)
					)
					(fill
						(type background)
					)
				)
				(text "BANK15"
					(at 17.78 2.54 0)
					(effects
						(font
							(size 1.27 1.27)
							(thickness 0.15)
						)
						(justify left bottom)
					)
				)
				(pin bidirectional line
					(at 0 0 0)
					(length 5.08)
					(name "IO_0_15"
						(effects
							(font
								(size 1.27 1.27)
							)
						)
					)
					(number "D12"
						(effects
							(font
								(size 1.27 1.27)
							)
						)
					)
				)
				(pin bidirectional line
					(at 0 -2.54 0)
					(length 5.08)
					(name "IO_L1P_T0_AD0P_15"
						(effects
							(font
								(size 1.27 1.27)
							)
						)
					)
					(number "G15"
						(effects
							(font
								(size 1.27 1.27)
							)
						)
					)
				)
				(pin bidirectional line
					(at 0 -5.08 0)
					(length 5.08)
					(name "IO_L1N_T0_AD0N_15"
						(effects
							(font
								(size 1.27 1.27)
							)
						)
					)
					(number "G16"
						(effects
							(font
								(size 1.27 1.27)
							)
						)
					)
				)
				(pin bidirectional line
					(at 0 -7.62 0)
					(length 5.08)
					(name "IO_L2P_T0_AD8P_15"
						(effects
							(font
								(size 1.27 1.27)
							)
						)
					)
					(number "C12"
						(effects
							(font
								(size 1.27 1.27)
							)
						)
					)
				)
				(pin bidirectional line
					(at 0 -10.16 0)
					(length 5.08)
					(name "IO_L2N_T0_AD8N_15"
						(effects
							(font
								(size 1.27 1.27)
							)
						)
					)
					(number "B12"
						(effects
							(font
								(size 1.27 1.27)
							)
						)
					)
				)
				(pin bidirectional line
					(at 0 -12.7 0)
					(length 5.08)
					(name "IO_L3P_T0_DQS_AD1P_15"
						(effects
							(font
								(size 1.27 1.27)
							)
						)
					)
					(number "F15"
						(effects
							(font
								(size 1.27 1.27)
							)
						)
					)
				)
				(pin bidirectional line
					(at 0 -15.24 0)
					(length 5.08)
					(name "IO_L3N_T0_DQS_AD1N_15"
						(effects
							(font
								(size 1.27 1.27)
							)
						)
					)
					(number "F16"
						(effects
							(font
								(size 1.27 1.27)
							)
						)
					)
				)
				(pin bidirectional line
					(at 0 -17.78 0)
					(length 5.08)
					(name "IO_L4P_T0_AD9P_15"
						(effects
							(font
								(size 1.27 1.27)
							)
						)
					)
					(number "A13"
						(effects
							(font
								(size 1.27 1.27)
							)
						)
					)
				)
				(pin bidirectional line
					(at 0 -20.32 0)
					(length 5.08)
					(name "IO_L4N_T0_AD9N_15"
						(effects
							(font
								(size 1.27 1.27)
							)
						)
					)
					(number "A14"
						(effects
							(font
								(size 1.27 1.27)
							)
						)
					)
				)
				(pin bidirectional line
					(at 0 -22.86 0)
					(length 5.08)
					(name "IO_L5P_T0_AD2P_15"
						(effects
							(font
								(size 1.27 1.27)
							)
						)
					)
					(number "C13"
						(effects
							(font
								(size 1.27 1.27)
							)
						)
					)
				)
				(pin bidirectional line
					(at 0 -25.4 0)
					(length 5.08)
					(name "IO_L5N_T0_AD2N_15"
						(effects
							(font
								(size 1.27 1.27)
							)
						)
					)
					(number "B13"
						(effects
							(font
								(size 1.27 1.27)
							)
						)
					)
				)
				(pin bidirectional line
					(at 0 -27.94 0)
					(length 5.08)
					(name "IO_L6P_T0_15"
						(effects
							(font
								(size 1.27 1.27)
							)
						)
					)
					(number "E14"
						(effects
							(font
								(size 1.27 1.27)
							)
						)
					)
				)
				(pin bidirectional line
					(at 0 -30.48 0)
					(length 5.08)
					(name "IO_L6N_T0_VREF_15"
						(effects
							(font
								(size 1.27 1.27)
							)
						)
					)
					(number "D14"
						(effects
							(font
								(size 1.27 1.27)
							)
						)
					)
				)
				(pin bidirectional line
					(at 0 -33.02 0)
					(length 5.08)
					(name "IO_L7P_T1_AD10P_15"
						(effects
							(font
								(size 1.27 1.27)
							)
						)
					)
					(number "C14"
						(effects
							(font
								(size 1.27 1.27)
							)
						)
					)
				)
				(pin bidirectional line
					(at 0 -35.56 0)
					(length 5.08)
					(name "IO_L7N_T1_AD10N_15"
						(effects
							(font
								(size 1.27 1.27)
							)
						)
					)
					(number "C15"
						(effects
							(font
								(size 1.27 1.27)
							)
						)
					)
				)
				(pin bidirectional line
					(at 0 -38.1 0)
					(length 5.08)
					(name "IO_L8P_T1_AD3P_15"
						(effects
							(font
								(size 1.27 1.27)
							)
						)
					)
					(number "B16"
						(effects
							(font
								(size 1.27 1.27)
							)
						)
					)
				)
				(pin bidirectional line
					(at 0 -40.64 0)
					(length 5.08)
					(name "IO_L8N_T1_AD3N_15"
						(effects
							(font
								(size 1.27 1.27)
							)
						)
					)
					(number "A16"
						(effects
							(font
								(size 1.27 1.27)
							)
						)
					)
				)
				(pin bidirectional line
					(at 0 -43.18 0)
					(length 5.08)
					(name "IO_L9P_T1_DQS_AD11P_15"
						(effects
							(font
								(size 1.27 1.27)
							)
						)
					)
					(number "B15"
						(effects
							(font
								(size 1.27 1.27)
							)
						)
					)
				)
				(pin bidirectional line
					(at 0 -45.72 0)
					(length 5.08)
					(name "IO_L9N_T1_DQS_AD11N_15"
						(effects
							(font
								(size 1.27 1.27)
							)
						)
					)
					(number "A15"
						(effects
							(font
								(size 1.27 1.27)
							)
						)
					)
				)
				(pin bidirectional line
					(at 0 -48.26 0)
					(length 5.08)
					(name "IO_L10P_T1_AD4P_15"
						(effects
							(font
								(size 1.27 1.27)
							)
						)
					)
					(number "B17"
						(effects
							(font
								(size 1.27 1.27)
							)
						)
					)
				)
				(pin bidirectional line
					(at 0 -50.8 0)
					(length 5.08)
					(name "IO_L10N_T1_AD4N_15"
						(effects
							(font
								(size 1.27 1.27)
							)
						)
					)
					(number "A18"
						(effects
							(font
								(size 1.27 1.27)
							)
						)
					)
				)
				(pin bidirectional line
					(at 0 -53.34 0)
					(length 5.08)
					(name "IO_L11P_T1_SRCC_AD12P_15"
						(effects
							(font
								(size 1.27 1.27)
							)
						)
					)
					(number "D15"
						(effects
							(font
								(size 1.27 1.27)
							)
						)
					)
				)
				(pin bidirectional line
					(at 0 -55.88 0)
					(length 5.08)
					(name "IO_L11N_T1_SRCC_AD12N_15"
						(effects
							(font
								(size 1.27 1.27)
							)
						)
					)
					(number "D16"
						(effects
							(font
								(size 1.27 1.27)
							)
						)
					)
				)
				(pin bidirectional line
					(at 0 -58.42 0)
					(length 5.08)
					(name "IO_L12P_T1_MRCC_AD5P_15"
						(effects
							(font
								(size 1.27 1.27)
							)
						)
					)
					(number "C17"
						(effects
							(font
								(size 1.27 1.27)
							)
						)
					)
				)
				(pin bidirectional line
					(at 0 -60.96 0)
					(length 5.08)
					(name "IO_L12N_T1_MRCC_AD5N_15"
						(effects
							(font
								(size 1.27 1.27)
							)
						)
					)
					(number "C18"
						(effects
							(font
								(size 1.27 1.27)
							)
						)
					)
				)
				(pin bidirectional line
					(at 0 -63.5 0)
					(length 5.08)
					(name "IO_L13P_T2_MRCC_15"
						(effects
							(font
								(size 1.27 1.27)
							)
						)
					)
					(number "E17"
						(effects
							(font
								(size 1.27 1.27)
							)
						)
					)
				)
				(pin bidirectional line
					(at 0 -66.04 0)
					(length 5.08)
					(name "IO_L13N_T2_MRCC_15"
						(effects
							(font
								(size 1.27 1.27)
							)
						)
					)
					(number "E18"
						(effects
							(font
								(size 1.27 1.27)
							)
						)
					)
				)
				(pin bidirectional line
					(at 0 -68.58 0)
					(length 5.08)
					(name "IO_L14P_T2_SRCC_15"
						(effects
							(font
								(size 1.27 1.27)
							)
						)
					)
					(number "E16"
						(effects
							(font
								(size 1.27 1.27)
							)
						)
					)
				)
				(pin bidirectional line
					(at 0 -71.12 0)
					(length 5.08)
					(name "IO_L14N_T2_SRCC_15"
						(effects
							(font
								(size 1.27 1.27)
							)
						)
					)
					(number "D17"
						(effects
							(font
								(size 1.27 1.27)
							)
						)
					)
				)
				(pin bidirectional line
					(at 0 -73.66 0)
					(length 5.08)
					(name "IO_L15P_T2_DQS_15"
						(effects
							(font
								(size 1.27 1.27)
							)
						)
					)
					(number "H17"
						(effects
							(font
								(size 1.27 1.27)
							)
						)
					)
				)
				(pin bidirectional line
					(at 0 -76.2 0)
					(length 5.08)
					(name "IO_L15N_T2_DQS_ADV_B_15"
						(effects
							(font
								(size 1.27 1.27)
							)
						)
					)
					(number "G17"
						(effects
							(font
								(size 1.27 1.27)
							)
						)
					)
				)
				(pin bidirectional line
					(at 0 -78.74 0)
					(length 5.08)
					(name "IO_L16P_T2_A28_15"
						(effects
							(font
								(size 1.27 1.27)
							)
						)
					)
					(number "J16"
						(effects
							(font
								(size 1.27 1.27)
							)
						)
					)
				)
				(pin bidirectional line
					(at 0 -81.28 0)
					(length 5.08)
					(name "IO_L16N_T2_A27_15"
						(effects
							(font
								(size 1.27 1.27)
							)
						)
					)
					(number "J17"
						(effects
							(font
								(size 1.27 1.27)
							)
						)
					)
				)
				(pin bidirectional line
					(at 0 -83.82 0)
					(length 5.08)
					(name "IO_L17P_T2_A26_15"
						(effects
							(font
								(size 1.27 1.27)
							)
						)
					)
					(number "F18"
						(effects
							(font
								(size 1.27 1.27)
							)
						)
					)
				)
				(pin bidirectional line
					(at 0 -86.36 0)
					(length 5.08)
					(name "IO_L17N_T2_A25_15"
						(effects
							(font
								(size 1.27 1.27)
							)
						)
					)
					(number "E19"
						(effects
							(font
								(size 1.27 1.27)
							)
						)
					)
				)
				(pin bidirectional line
					(at 0 -88.9 0)
					(length 5.08)
					(name "IO_L18P_T2_A24_15"
						(effects
							(font
								(size 1.27 1.27)
							)
						)
					)
					(number "D19"
						(effects
							(font
								(size 1.27 1.27)
							)
						)
					)
				)
				(pin bidirectional line
					(at 0 -91.44 0)
					(length 5.08)
					(name "IO_L18N_T2_A23_15"
						(effects
							(font
								(size 1.27 1.27)
							)
						)
					)
					(number "D20"
						(effects
							(font
								(size 1.27 1.27)
							)
						)
					)
				)
				(pin bidirectional line
					(at 0 -93.98 0)
					(length 5.08)
					(name "IO_L19P_T3_A22_15"
						(effects
							(font
								(size 1.27 1.27)
							)
						)
					)
					(number "C19"
						(effects
							(font
								(size 1.27 1.27)
							)
						)
					)
				)
				(pin bidirectional line
					(at 0 -96.52 0)
					(length 5.08)
					(name "IO_L19N_T3_A21_VREF_15"
						(effects
							(font
								(size 1.27 1.27)
							)
						)
					)
					(number "C20"
						(effects
							(font
								(size 1.27 1.27)
							)
						)
					)
				)
				(pin bidirectional line
					(at 0 -99.06 0)
					(length 5.08)
					(name "IO_L20P_T3_A20_15"
						(effects
							(font
								(size 1.27 1.27)
							)
						)
					)
					(number "B18"
						(effects
							(font
								(size 1.27 1.27)
							)
						)
					)
				)
				(pin bidirectional line
					(at 0 -101.6 0)
					(length 5.08)
					(name "IO_L20N_T3_A19_15"
						(effects
							(font
								(size 1.27 1.27)
							)
						)
					)
					(number "A19"
						(effects
							(font
								(size 1.27 1.27)
							)
						)
					)
				)
				(pin bidirectional line
					(at 0 -104.14 0)
					(length 5.08)
					(name "IO_L21P_T3_DQS_15"
						(effects
							(font
								(size 1.27 1.27)
							)
						)
					)
					(number "C22"
						(effects
							(font
								(size 1.27 1.27)
							)
						)
					)
				)
				(pin bidirectional line
					(at 0 -106.68 0)
					(length 5.08)
					(name "IO_L21N_T3_DQS_A18_15"
						(effects
							(font
								(size 1.27 1.27)
							)
						)
					)
					(number "B22"
						(effects
							(font
								(size 1.27 1.27)
							)
						)
					)
				)
				(pin bidirectional line
					(at 0 -109.22 0)
					(length 5.08)
					(name "IO_L22P_T3_A17_15"
						(effects
							(font
								(size 1.27 1.27)
							)
						)
					)
					(number "A20"
						(effects
							(font
								(size 1.27 1.27)
							)
						)
					)
				)
				(pin bidirectional line
					(at 0 -111.76 0)
					(length 5.08)
					(name "IO_L22N_T3_A16_15"
						(effects
							(font
								(size 1.27 1.27)
							)
						)
					)
					(number "A21"
						(effects
							(font
								(size 1.27 1.27)
							)
						)
					)
				)
				(pin bidirectional line
					(at 0 -114.3 0)
					(length 5.08)
					(name "IO_L23P_T3_FOE_B_15"
						(effects
							(font
								(size 1.27 1.27)
							)
						)
					)
					(number "D21"
						(effects
							(font
								(size 1.27 1.27)
							)
						)
					)
				)
				(pin bidirectional line
					(at 0 -116.84 0)
					(length 5.08)
					(name "IO_L23N_T3_FWE_B_15"
						(effects
							(font
								(size 1.27 1.27)
							)
						)
					)
					(number "D22"
						(effects
							(font
								(size 1.27 1.27)
							)
						)
					)
				)
				(pin bidirectional line
					(at 0 -119.38 0)
					(length 5.08)
					(name "IO_L24P_T3_RS1_15"
						(effects
							(font
								(size 1.27 1.27)
							)
						)
					)
					(number "B20"
						(effects
							(font
								(size 1.27 1.27)
							)
						)
					)
				)
				(pin bidirectional line
					(at 0 -121.92 0)
					(length 5.08)
					(name "IO_L24N_T3_RS0_15"
						(effects
							(font
								(size 1.27 1.27)
							)
						)
					)
					(number "B21"
						(effects
							(font
								(size 1.27 1.27)
							)
						)
					)
				)
				(pin bidirectional line
					(at 0 -124.46 0)
					(length 5.08)
					(name "IO_25_15"
						(effects
							(font
								(size 1.27 1.27)
							)
						)
					)
					(number "H15"
						(effects
							(font
								(size 1.27 1.27)
							)
						)
					)
				)
			)
			(symbol "XC7K70T-FBG484_8_1"
				(rectangle
					(start 5.08 5.08)
					(end 39.37 -127)
					(stroke
						(width 0.254)
						(type default)
					)
					(fill
						(type background)
					)
				)
				(text "BANK14"
					(at 17.78 2.54 0)
					(effects
						(font
							(size 1.27 1.27)
							(thickness 0.15)
						)
						(justify left bottom)
					)
				)
				(pin bidirectional line
					(at 0 0 0)
					(length 5.08)
					(name "IO_0_14"
						(effects
							(font
								(size 1.27 1.27)
							)
						)
					)
					(number "K16"
						(effects
							(font
								(size 1.27 1.27)
							)
						)
					)
				)
				(pin bidirectional line
					(at 0 -2.54 0)
					(length 5.08)
					(name "IO_L1P_T0_D00_MOSI_14"
						(effects
							(font
								(size 1.27 1.27)
							)
						)
					)
					(number "H18"
						(effects
							(font
								(size 1.27 1.27)
							)
						)
					)
				)
				(pin bidirectional line
					(at 0 -5.08 0)
					(length 5.08)
					(name "IO_L1N_T0_D01_DIN_14"
						(effects
							(font
								(size 1.27 1.27)
							)
						)
					)
					(number "H19"
						(effects
							(font
								(size 1.27 1.27)
							)
						)
					)
				)
				(pin bidirectional line
					(at 0 -7.62 0)
					(length 5.08)
					(name "IO_L2P_T0_D02_14"
						(effects
							(font
								(size 1.27 1.27)
							)
						)
					)
					(number "G18"
						(effects
							(font
								(size 1.27 1.27)
							)
						)
					)
				)
				(pin bidirectional line
					(at 0 -10.16 0)
					(length 5.08)
					(name "IO_L2N_T0_D03_14"
						(effects
							(font
								(size 1.27 1.27)
							)
						)
					)
					(number "F19"
						(effects
							(font
								(size 1.27 1.27)
							)
						)
					)
				)
				(pin bidirectional line
					(at 0 -12.7 0)
					(length 5.08)
					(name "IO_L3P_T0_DQS_PUDC_B_14"
						(effects
							(font
								(size 1.27 1.27)
							)
						)
					)
					(number "K18"
						(effects
							(font
								(size 1.27 1.27)
							)
						)
					)
				)
				(pin bidirectional line
					(at 0 -15.24 0)
					(length 5.08)
					(name "IO_L3N_T0_DQS_EMCCLK_14"
						(effects
							(font
								(size 1.27 1.27)
							)
						)
					)
					(number "J19"
						(effects
							(font
								(size 1.27 1.27)
							)
						)
					)
				)
				(pin bidirectional line
					(at 0 -17.78 0)
					(length 5.08)
					(name "IO_L4P_T0_D04_14"
						(effects
							(font
								(size 1.27 1.27)
							)
						)
					)
					(number "G20"
						(effects
							(font
								(size 1.27 1.27)
							)
						)
					)
				)
				(pin bidirectional line
					(at 0 -20.32 0)
					(length 5.08)
					(name "IO_L4N_T0_D05_14"
						(effects
							(font
								(size 1.27 1.27)
							)
						)
					)
					(number "F20"
						(effects
							(font
								(size 1.27 1.27)
							)
						)
					)
				)
				(pin bidirectional line
					(at 0 -22.86 0)
					(length 5.08)
					(name "IO_L5P_T0_D06_14"
						(effects
							(font
								(size 1.27 1.27)
							)
						)
					)
					(number "L18"
						(effects
							(font
								(size 1.27 1.27)
							)
						)
					)
				)
				(pin bidirectional line
					(at 0 -25.4 0)
					(length 5.08)
					(name "IO_L5N_T0_D07_14"
						(effects
							(font
								(size 1.27 1.27)
							)
						)
					)
					(number "K19"
						(effects
							(font
								(size 1.27 1.27)
							)
						)
					)
				)
				(pin bidirectional line
					(at 0 -27.94 0)
					(length 5.08)
					(name "IO_L6P_T0_FCS_B_14"
						(effects
							(font
								(size 1.27 1.27)
							)
						)
					)
					(number "L16"
						(effects
							(font
								(size 1.27 1.27)
							)
						)
					)
				)
				(pin bidirectional line
					(at 0 -30.48 0)
					(length 5.08)
					(name "IO_L6N_T0_D08_VREF_14"
						(effects
							(font
								(size 1.27 1.27)
							)
						)
					)
					(number "K17"
						(effects
							(font
								(size 1.27 1.27)
							)
						)
					)
				)
				(pin bidirectional line
					(at 0 -33.02 0)
					(length 5.08)
					(name "IO_L7P_T1_D09_14"
						(effects
							(font
								(size 1.27 1.27)
							)
						)
					)
					(number "E21"
						(effects
							(font
								(size 1.27 1.27)
							)
						)
					)
				)
				(pin bidirectional line
					(at 0 -35.56 0)
					(length 5.08)
					(name "IO_L7N_T1_D10_14"
						(effects
							(font
								(size 1.27 1.27)
							)
						)
					)
					(number "E22"
						(effects
							(font
								(size 1.27 1.27)
							)
						)
					)
				)
				(pin bidirectional line
					(at 0 -38.1 0)
					(length 5.08)
					(name "IO_L8P_T1_D11_14"
						(effects
							(font
								(size 1.27 1.27)
							)
						)
					)
					(number "H22"
						(effects
							(font
								(size 1.27 1.27)
							)
						)
					)
				)
				(pin bidirectional line
					(at 0 -40.64 0)
					(length 5.08)
					(name "IO_L8N_T1_D12_14"
						(effects
							(font
								(size 1.27 1.27)
							)
						)
					)
					(number "G22"
						(effects
							(font
								(size 1.27 1.27)
							)
						)
					)
				)
				(pin bidirectional line
					(at 0 -43.18 0)
					(length 5.08)
					(name "IO_L9P_T1_DQS_14"
						(effects
							(font
								(size 1.27 1.27)
							)
						)
					)
					(number "G21"
						(effects
							(font
								(size 1.27 1.27)
							)
						)
					)
				)
				(pin bidirectional line
					(at 0 -45.72 0)
					(length 5.08)
					(name "IO_L9N_T1_DQS_D13_14"
						(effects
							(font
								(size 1.27 1.27)
							)
						)
					)
					(number "F21"
						(effects
							(font
								(size 1.27 1.27)
							)
						)
					)
				)
				(pin bidirectional line
					(at 0 -48.26 0)
					(length 5.08)
					(name "IO_L10P_T1_D14_14"
						(effects
							(font
								(size 1.27 1.27)
							)
						)
					)
					(number "J21"
						(effects
							(font
								(size 1.27 1.27)
							)
						)
					)
				)
				(pin bidirectional line
					(at 0 -50.8 0)
					(length 5.08)
					(name "IO_L10N_T1_D15_14"
						(effects
							(font
								(size 1.27 1.27)
							)
						)
					)
					(number "J22"
						(effects
							(font
								(size 1.27 1.27)
							)
						)
					)
				)
				(pin bidirectional line
					(at 0 -53.34 0)
					(length 5.08)
					(name "IO_L11P_T1_SRCC_14"
						(effects
							(font
								(size 1.27 1.27)
							)
						)
					)
					(number "J20"
						(effects
							(font
								(size 1.27 1.27)
							)
						)
					)
				)
				(pin bidirectional line
					(at 0 -55.88 0)
					(length 5.08)
					(name "IO_L11N_T1_SRCC_14"
						(effects
							(font
								(size 1.27 1.27)
							)
						)
					)
					(number "H20"
						(effects
							(font
								(size 1.27 1.27)
							)
						)
					)
				)
				(pin bidirectional line
					(at 0 -58.42 0)
					(length 5.08)
					(name "IO_L12P_T1_MRCC_14"
						(effects
							(font
								(size 1.27 1.27)
							)
						)
					)
					(number "L19"
						(effects
							(font
								(size 1.27 1.27)
							)
						)
					)
				)
				(pin bidirectional line
					(at 0 -60.96 0)
					(length 5.08)
					(name "IO_L12N_T1_MRCC_14"
						(effects
							(font
								(size 1.27 1.27)
							)
						)
					)
					(number "L20"
						(effects
							(font
								(size 1.27 1.27)
							)
						)
					)
				)
				(pin bidirectional line
					(at 0 -63.5 0)
					(length 5.08)
					(name "IO_L13P_T2_MRCC_14"
						(effects
							(font
								(size 1.27 1.27)
							)
						)
					)
					(number "N18"
						(effects
							(font
								(size 1.27 1.27)
							)
						)
					)
				)
				(pin bidirectional line
					(at 0 -66.04 0)
					(length 5.08)
					(name "IO_L13N_T2_MRCC_14"
						(effects
							(font
								(size 1.27 1.27)
							)
						)
					)
					(number "N19"
						(effects
							(font
								(size 1.27 1.27)
							)
						)
					)
				)
				(pin bidirectional line
					(at 0 -68.58 0)
					(length 5.08)
					(name "IO_L14P_T2_SRCC_14"
						(effects
							(font
								(size 1.27 1.27)
							)
						)
					)
					(number "M17"
						(effects
							(font
								(size 1.27 1.27)
							)
						)
					)
				)
				(pin bidirectional line
					(at 0 -71.12 0)
					(length 5.08)
					(name "IO_L14N_T2_SRCC_14"
						(effects
							(font
								(size 1.27 1.27)
							)
						)
					)
					(number "M18"
						(effects
							(font
								(size 1.27 1.27)
							)
						)
					)
				)
				(pin bidirectional line
					(at 0 -73.66 0)
					(length 5.08)
					(name "IO_L15P_T2_DQS_RDWR_B_14"
						(effects
							(font
								(size 1.27 1.27)
							)
						)
					)
					(number "N22"
						(effects
							(font
								(size 1.27 1.27)
							)
						)
					)
				)
				(pin bidirectional line
					(at 0 -76.2 0)
					(length 5.08)
					(name "IO_L15N_T2_DQS_DOUT_CSO_B_14"
						(effects
							(font
								(size 1.27 1.27)
							)
						)
					)
					(number "M22"
						(effects
							(font
								(size 1.27 1.27)
							)
						)
					)
				)
				(pin bidirectional line
					(at 0 -78.74 0)
					(length 5.08)
					(name "IO_L16P_T2_CSI_B_14"
						(effects
							(font
								(size 1.27 1.27)
							)
						)
					)
					(number "K21"
						(effects
							(font
								(size 1.27 1.27)
							)
						)
					)
				)
				(pin bidirectional line
					(at 0 -81.28 0)
					(length 5.08)
					(name "IO_L16N_T2_A15_D31_14"
						(effects
							(font
								(size 1.27 1.27)
							)
						)
					)
					(number "K22"
						(effects
							(font
								(size 1.27 1.27)
							)
						)
					)
				)
				(pin bidirectional line
					(at 0 -83.82 0)
					(length 5.08)
					(name "IO_L17P_T2_A14_D30_14"
						(effects
							(font
								(size 1.27 1.27)
							)
						)
					)
					(number "N20"
						(effects
							(font
								(size 1.27 1.27)
							)
						)
					)
				)
				(pin bidirectional line
					(at 0 -86.36 0)
					(length 5.08)
					(name "IO_L17N_T2_A13_D29_14"
						(effects
							(font
								(size 1.27 1.27)
							)
						)
					)
					(number "M21"
						(effects
							(font
								(size 1.27 1.27)
							)
						)
					)
				)
				(pin bidirectional line
					(at 0 -88.9 0)
					(length 5.08)
					(name "IO_L18P_T2_A12_D28_14"
						(effects
							(font
								(size 1.27 1.27)
							)
						)
					)
					(number "M20"
						(effects
							(font
								(size 1.27 1.27)
							)
						)
					)
				)
				(pin bidirectional line
					(at 0 -91.44 0)
					(length 5.08)
					(name "IO_L18N_T2_A11_D27_14"
						(effects
							(font
								(size 1.27 1.27)
							)
						)
					)
					(number "L21"
						(effects
							(font
								(size 1.27 1.27)
							)
						)
					)
				)
				(pin bidirectional line
					(at 0 -93.98 0)
					(length 5.08)
					(name "IO_L19P_T3_A10_D26_14"
						(effects
							(font
								(size 1.27 1.27)
							)
						)
					)
					(number "R18"
						(effects
							(font
								(size 1.27 1.27)
							)
						)
					)
				)
				(pin bidirectional line
					(at 0 -96.52 0)
					(length 5.08)
					(name "IO_L19N_T3_A09_D25_VREF_14"
						(effects
							(font
								(size 1.27 1.27)
							)
						)
					)
					(number "R19"
						(effects
							(font
								(size 1.27 1.27)
							)
						)
					)
				)
				(pin bidirectional line
					(at 0 -99.06 0)
					(length 5.08)
					(name "IO_L20P_T3_A08_D24_14"
						(effects
							(font
								(size 1.27 1.27)
							)
						)
					)
					(number "P19"
						(effects
							(font
								(size 1.27 1.27)
							)
						)
					)
				)
				(pin bidirectional line
					(at 0 -101.6 0)
					(length 5.08)
					(name "IO_L20N_T3_A07_D23_14"
						(effects
							(font
								(size 1.27 1.27)
							)
						)
					)
					(number "P20"
						(effects
							(font
								(size 1.27 1.27)
							)
						)
					)
				)
				(pin bidirectional line
					(at 0 -104.14 0)
					(length 5.08)
					(name "IO_L21P_T3_DQS_14"
						(effects
							(font
								(size 1.27 1.27)
							)
						)
					)
					(number "R17"
						(effects
							(font
								(size 1.27 1.27)
							)
						)
					)
				)
				(pin bidirectional line
					(at 0 -106.68 0)
					(length 5.08)
					(name "IO_L21N_T3_DQS_A06_D22_14"
						(effects
							(font
								(size 1.27 1.27)
							)
						)
					)
					(number "P17"
						(effects
							(font
								(size 1.27 1.27)
							)
						)
					)
				)
				(pin bidirectional line
					(at 0 -109.22 0)
					(length 5.08)
					(name "IO_L22P_T3_A05_D21_14"
						(effects
							(font
								(size 1.27 1.27)
							)
						)
					)
					(number "P21"
						(effects
							(font
								(size 1.27 1.27)
							)
						)
					)
				)
				(pin bidirectional line
					(at 0 -111.76 0)
					(length 5.08)
					(name "IO_L22N_T3_A04_D20_14"
						(effects
							(font
								(size 1.27 1.27)
							)
						)
					)
					(number "P22"
						(effects
							(font
								(size 1.27 1.27)
							)
						)
					)
				)
				(pin bidirectional line
					(at 0 -114.3 0)
					(length 5.08)
					(name "IO_L23P_T3_A03_D19_14"
						(effects
							(font
								(size 1.27 1.27)
							)
						)
					)
					(number "P16"
						(effects
							(font
								(size 1.27 1.27)
							)
						)
					)
				)
				(pin bidirectional line
					(at 0 -116.84 0)
					(length 5.08)
					(name "IO_L23N_T3_A02_D18_14"
						(effects
							(font
								(size 1.27 1.27)
							)
						)
					)
					(number "N17"
						(effects
							(font
								(size 1.27 1.27)
							)
						)
					)
				)
				(pin bidirectional line
					(at 0 -119.38 0)
					(length 5.08)
					(name "IO_L24P_T3_A01_D17_14"
						(effects
							(font
								(size 1.27 1.27)
							)
						)
					)
					(number "R21"
						(effects
							(font
								(size 1.27 1.27)
							)
						)
					)
				)
				(pin bidirectional line
					(at 0 -121.92 0)
					(length 5.08)
					(name "IO_L24N_T3_A00_D16_14"
						(effects
							(font
								(size 1.27 1.27)
							)
						)
					)
					(number "R22"
						(effects
							(font
								(size 1.27 1.27)
							)
						)
					)
				)
				(pin bidirectional line
					(at 0 -124.46 0)
					(length 5.08)
					(name "IO_25_14"
						(effects
							(font
								(size 1.27 1.27)
							)
						)
					)
					(number "M16"
						(effects
							(font
								(size 1.27 1.27)
							)
						)
					)
				)
			)
			(symbol "XC7K70T-FBG484_9_1"
				(rectangle
					(start 5.08 5.08)
					(end 39.37 -127)
					(stroke
						(width 0.254)
						(type default)
					)
					(fill
						(type background)
					)
				)
				(text "BANK13"
					(at 17.78 2.54 0)
					(effects
						(font
							(size 1.27 1.27)
							(thickness 0.15)
						)
						(justify left bottom)
					)
				)
				(pin bidirectional line
					(at 0 0 0)
					(length 5.08)
					(name "IO_0_13"
						(effects
							(font
								(size 1.27 1.27)
							)
						)
					)
					(number "T19"
						(effects
							(font
								(size 1.27 1.27)
							)
						)
					)
				)
				(pin bidirectional line
					(at 0 -2.54 0)
					(length 5.08)
					(name "IO_L1P_T0_13"
						(effects
							(font
								(size 1.27 1.27)
							)
						)
					)
					(number "T21"
						(effects
							(font
								(size 1.27 1.27)
							)
						)
					)
				)
				(pin bidirectional line
					(at 0 -5.08 0)
					(length 5.08)
					(name "IO_L1N_T0_13"
						(effects
							(font
								(size 1.27 1.27)
							)
						)
					)
					(number "U21"
						(effects
							(font
								(size 1.27 1.27)
							)
						)
					)
				)
				(pin bidirectional line
					(at 0 -7.62 0)
					(length 5.08)
					(name "IO_L2P_T0_13"
						(effects
							(font
								(size 1.27 1.27)
							)
						)
					)
					(number "U22"
						(effects
							(font
								(size 1.27 1.27)
							)
						)
					)
				)
				(pin bidirectional line
					(at 0 -10.16 0)
					(length 5.08)
					(name "IO_L2N_T0_13"
						(effects
							(font
								(size 1.27 1.27)
							)
						)
					)
					(number "V22"
						(effects
							(font
								(size 1.27 1.27)
							)
						)
					)
				)
				(pin bidirectional line
					(at 0 -12.7 0)
					(length 5.08)
					(name "IO_L3P_T0_DQS_13"
						(effects
							(font
								(size 1.27 1.27)
							)
						)
					)
					(number "T18"
						(effects
							(font
								(size 1.27 1.27)
							)
						)
					)
				)
				(pin bidirectional line
					(at 0 -15.24 0)
					(length 5.08)
					(name "IO_L3N_T0_DQS_13"
						(effects
							(font
								(size 1.27 1.27)
							)
						)
					)
					(number "U18"
						(effects
							(font
								(size 1.27 1.27)
							)
						)
					)
				)
				(pin bidirectional line
					(at 0 -17.78 0)
					(length 5.08)
					(name "IO_L4P_T0_13"
						(effects
							(font
								(size 1.27 1.27)
							)
						)
					)
					(number "W21"
						(effects
							(font
								(size 1.27 1.27)
							)
						)
					)
				)
				(pin bidirectional line
					(at 0 -20.32 0)
					(length 5.08)
					(name "IO_L4N_T0_13"
						(effects
							(font
								(size 1.27 1.27)
							)
						)
					)
					(number "W22"
						(effects
							(font
								(size 1.27 1.27)
							)
						)
					)
				)
				(pin bidirectional line
					(at 0 -22.86 0)
					(length 5.08)
					(name "IO_L5P_T0_13"
						(effects
							(font
								(size 1.27 1.27)
							)
						)
					)
					(number "U17"
						(effects
							(font
								(size 1.27 1.27)
							)
						)
					)
				)
				(pin bidirectional line
					(at 0 -25.4 0)
					(length 5.08)
					(name "IO_L5N_T0_13"
						(effects
							(font
								(size 1.27 1.27)
							)
						)
					)
					(number "V18"
						(effects
							(font
								(size 1.27 1.27)
							)
						)
					)
				)
				(pin bidirectional line
					(at 0 -27.94 0)
					(length 5.08)
					(name "IO_L6P_T0_13"
						(effects
							(font
								(size 1.27 1.27)
							)
						)
					)
					(number "T20"
						(effects
							(font
								(size 1.27 1.27)
							)
						)
					)
				)
				(pin bidirectional line
					(at 0 -30.48 0)
					(length 5.08)
					(name "IO_L6N_T0_VREF_13"
						(effects
							(font
								(size 1.27 1.27)
							)
						)
					)
					(number "U20"
						(effects
							(font
								(size 1.27 1.27)
							)
						)
					)
				)
				(pin bidirectional line
					(at 0 -33.02 0)
					(length 5.08)
					(name "IO_L7P_T1_13"
						(effects
							(font
								(size 1.27 1.27)
							)
						)
					)
					(number "Y21"
						(effects
							(font
								(size 1.27 1.27)
							)
						)
					)
				)
				(pin bidirectional line
					(at 0 -35.56 0)
					(length 5.08)
					(name "IO_L7N_T1_13"
						(effects
							(font
								(size 1.27 1.27)
							)
						)
					)
					(number "Y22"
						(effects
							(font
								(size 1.27 1.27)
							)
						)
					)
				)
				(pin bidirectional line
					(at 0 -38.1 0)
					(length 5.08)
					(name "IO_L8P_T1_13"
						(effects
							(font
								(size 1.27 1.27)
							)
						)
					)
					(number "AA20"
						(effects
							(font
								(size 1.27 1.27)
							)
						)
					)
				)
				(pin bidirectional line
					(at 0 -40.64 0)
					(length 5.08)
					(name "IO_L8N_T1_13"
						(effects
							(font
								(size 1.27 1.27)
							)
						)
					)
					(number "AB21"
						(effects
							(font
								(size 1.27 1.27)
							)
						)
					)
				)
				(pin bidirectional line
					(at 0 -43.18 0)
					(length 5.08)
					(name "IO_L9P_T1_DQS_13"
						(effects
							(font
								(size 1.27 1.27)
							)
						)
					)
					(number "AA21"
						(effects
							(font
								(size 1.27 1.27)
							)
						)
					)
				)
				(pin bidirectional line
					(at 0 -45.72 0)
					(length 5.08)
					(name "IO_L9N_T1_DQS_13"
						(effects
							(font
								(size 1.27 1.27)
							)
						)
					)
					(number "AB22"
						(effects
							(font
								(size 1.27 1.27)
							)
						)
					)
				)
				(pin bidirectional line
					(at 0 -48.26 0)
					(length 5.08)
					(name "IO_L10P_T1_13"
						(effects
							(font
								(size 1.27 1.27)
							)
						)
					)
					(number "AA19"
						(effects
							(font
								(size 1.27 1.27)
							)
						)
					)
				)
				(pin bidirectional line
					(at 0 -50.8 0)
					(length 5.08)
					(name "IO_L10N_T1_13"
						(effects
							(font
								(size 1.27 1.27)
							)
						)
					)
					(number "AB20"
						(effects
							(font
								(size 1.27 1.27)
							)
						)
					)
				)
				(pin bidirectional line
					(at 0 -53.34 0)
					(length 5.08)
					(name "IO_L11P_T1_SRCC_13"
						(effects
							(font
								(size 1.27 1.27)
							)
						)
					)
					(number "V20"
						(effects
							(font
								(size 1.27 1.27)
							)
						)
					)
				)
				(pin bidirectional line
					(at 0 -55.88 0)
					(length 5.08)
					(name "IO_L11N_T1_SRCC_13"
						(effects
							(font
								(size 1.27 1.27)
							)
						)
					)
					(number "W20"
						(effects
							(font
								(size 1.27 1.27)
							)
						)
					)
				)
				(pin bidirectional line
					(at 0 -58.42 0)
					(length 5.08)
					(name "IO_L12P_T1_MRCC_13"
						(effects
							(font
								(size 1.27 1.27)
							)
						)
					)
					(number "V19"
						(effects
							(font
								(size 1.27 1.27)
							)
						)
					)
				)
				(pin bidirectional line
					(at 0 -60.96 0)
					(length 5.08)
					(name "IO_L12N_T1_MRCC_13"
						(effects
							(font
								(size 1.27 1.27)
							)
						)
					)
					(number "W19"
						(effects
							(font
								(size 1.27 1.27)
							)
						)
					)
				)
				(pin bidirectional line
					(at 0 -63.5 0)
					(length 5.08)
					(name "IO_L13P_T2_MRCC_13"
						(effects
							(font
								(size 1.27 1.27)
							)
						)
					)
					(number "Y18"
						(effects
							(font
								(size 1.27 1.27)
							)
						)
					)
				)
				(pin bidirectional line
					(at 0 -66.04 0)
					(length 5.08)
					(name "IO_L13N_T2_MRCC_13"
						(effects
							(font
								(size 1.27 1.27)
							)
						)
					)
					(number "Y19"
						(effects
							(font
								(size 1.27 1.27)
							)
						)
					)
				)
				(pin bidirectional line
					(at 0 -68.58 0)
					(length 5.08)
					(name "IO_L14P_T2_SRCC_13"
						(effects
							(font
								(size 1.27 1.27)
							)
						)
					)
					(number "W17"
						(effects
							(font
								(size 1.27 1.27)
							)
						)
					)
				)
				(pin bidirectional line
					(at 0 -71.12 0)
					(length 5.08)
					(name "IO_L14N_T2_SRCC_13"
						(effects
							(font
								(size 1.27 1.27)
							)
						)
					)
					(number "Y17"
						(effects
							(font
								(size 1.27 1.27)
							)
						)
					)
				)
				(pin bidirectional line
					(at 0 -73.66 0)
					(length 5.08)
					(name "IO_L15P_T2_DQS_13"
						(effects
							(font
								(size 1.27 1.27)
							)
						)
					)
					(number "AA18"
						(effects
							(font
								(size 1.27 1.27)
							)
						)
					)
				)
				(pin bidirectional line
					(at 0 -76.2 0)
					(length 5.08)
					(name "IO_L15N_T2_DQS_13"
						(effects
							(font
								(size 1.27 1.27)
							)
						)
					)
					(number "AB18"
						(effects
							(font
								(size 1.27 1.27)
							)
						)
					)
				)
				(pin bidirectional line
					(at 0 -78.74 0)
					(length 5.08)
					(name "IO_L16P_T2_13"
						(effects
							(font
								(size 1.27 1.27)
							)
						)
					)
					(number "AB15"
						(effects
							(font
								(size 1.27 1.27)
							)
						)
					)
				)
				(pin bidirectional line
					(at 0 -81.28 0)
					(length 5.08)
					(name "IO_L16N_T2_13"
						(effects
							(font
								(size 1.27 1.27)
							)
						)
					)
					(number "AB16"
						(effects
							(font
								(size 1.27 1.27)
							)
						)
					)
				)
				(pin bidirectional line
					(at 0 -83.82 0)
					(length 5.08)
					(name "IO_L17P_T2_13"
						(effects
							(font
								(size 1.27 1.27)
							)
						)
					)
					(number "AA16"
						(effects
							(font
								(size 1.27 1.27)
							)
						)
					)
				)
				(pin bidirectional line
					(at 0 -86.36 0)
					(length 5.08)
					(name "IO_L17N_T2_13"
						(effects
							(font
								(size 1.27 1.27)
							)
						)
					)
					(number "AB17"
						(effects
							(font
								(size 1.27 1.27)
							)
						)
					)
				)
				(pin bidirectional line
					(at 0 -88.9 0)
					(length 5.08)
					(name "IO_L18P_T2_13"
						(effects
							(font
								(size 1.27 1.27)
							)
						)
					)
					(number "AA14"
						(effects
							(font
								(size 1.27 1.27)
							)
						)
					)
				)
				(pin bidirectional line
					(at 0 -91.44 0)
					(length 5.08)
					(name "IO_L18N_T2_13"
						(effects
							(font
								(size 1.27 1.27)
							)
						)
					)
					(number "AA15"
						(effects
							(font
								(size 1.27 1.27)
							)
						)
					)
				)
				(pin bidirectional line
					(at 0 -93.98 0)
					(length 5.08)
					(name "IO_L19P_T3_13"
						(effects
							(font
								(size 1.27 1.27)
							)
						)
					)
					(number "U16"
						(effects
							(font
								(size 1.27 1.27)
							)
						)
					)
				)
				(pin bidirectional line
					(at 0 -96.52 0)
					(length 5.08)
					(name "IO_L19N_T3_VREF_13"
						(effects
							(font
								(size 1.27 1.27)
							)
						)
					)
					(number "V17"
						(effects
							(font
								(size 1.27 1.27)
							)
						)
					)
				)
				(pin bidirectional line
					(at 0 -99.06 0)
					(length 5.08)
					(name "IO_L20P_T3_13"
						(effects
							(font
								(size 1.27 1.27)
							)
						)
					)
					(number "R16"
						(effects
							(font
								(size 1.27 1.27)
							)
						)
					)
				)
				(pin bidirectional line
					(at 0 -101.6 0)
					(length 5.08)
					(name "IO_L20N_T3_13"
						(effects
							(font
								(size 1.27 1.27)
							)
						)
					)
					(number "T16"
						(effects
							(font
								(size 1.27 1.27)
							)
						)
					)
				)
				(pin bidirectional line
					(at 0 -104.14 0)
					(length 5.08)
					(name "IO_L21P_T3_DQS_13"
						(effects
							(font
								(size 1.27 1.27)
							)
						)
					)
					(number "W16"
						(effects
							(font
								(size 1.27 1.27)
							)
						)
					)
				)
				(pin bidirectional line
					(at 0 -106.68 0)
					(length 5.08)
					(name "IO_L21N_T3_DQS_13"
						(effects
							(font
								(size 1.27 1.27)
							)
						)
					)
					(number "Y16"
						(effects
							(font
								(size 1.27 1.27)
							)
						)
					)
				)
				(pin bidirectional line
					(at 0 -109.22 0)
					(length 5.08)
					(name "IO_L22P_T3_13"
						(effects
							(font
								(size 1.27 1.27)
							)
						)
					)
					(number "W14"
						(effects
							(font
								(size 1.27 1.27)
							)
						)
					)
				)
				(pin bidirectional line
					(at 0 -111.76 0)
					(length 5.08)
					(name "IO_L22N_T3_13"
						(effects
							(font
								(size 1.27 1.27)
							)
						)
					)
					(number "Y14"
						(effects
							(font
								(size 1.27 1.27)
							)
						)
					)
				)
				(pin bidirectional line
					(at 0 -114.3 0)
					(length 5.08)
					(name "IO_L23P_T3_13"
						(effects
							(font
								(size 1.27 1.27)
							)
						)
					)
					(number "V15"
						(effects
							(font
								(size 1.27 1.27)
							)
						)
					)
				)
				(pin bidirectional line
					(at 0 -116.84 0)
					(length 5.08)
					(name "IO_L23N_T3_13"
						(effects
							(font
								(size 1.27 1.27)
							)
						)
					)
					(number "W15"
						(effects
							(font
								(size 1.27 1.27)
							)
						)
					)
				)
				(pin bidirectional line
					(at 0 -119.38 0)
					(length 5.08)
					(name "IO_L24P_T3_13"
						(effects
							(font
								(size 1.27 1.27)
							)
						)
					)
					(number "T15"
						(effects
							(font
								(size 1.27 1.27)
							)
						)
					)
				)
				(pin bidirectional line
					(at 0 -121.92 0)
					(length 5.08)
					(name "IO_L24N_T3_13"
						(effects
							(font
								(size 1.27 1.27)
							)
						)
					)
					(number "U15"
						(effects
							(font
								(size 1.27 1.27)
							)
						)
					)
				)
				(pin bidirectional line
					(at 0 -124.46 0)
					(length 5.08)
					(name "IO_25_13"
						(effects
							(font
								(size 1.27 1.27)
							)
						)
					)
					(number "V14"
						(effects
							(font
								(size 1.27 1.27)
							)
						)
					)
				)
			)
		)
	(symbol "antmicroFerriteBeadsandChips:FB_120Z_2A_Murata-BLM18PG_0603"
			(pin_numbers
				(hide yes)
			)
			(pin_names
				(hide yes)
			)
			(exclude_from_sim no)
			(in_bom yes)
			(on_board yes)
			(property "Reference" "FB"
				(at 15.24 -2.54 0)
				(effects
					(font
						(size 1.27 1.27)
						(thickness 0.15)
					)
					(justify left bottom)
				)
			)
			(property "Value" "FB_120Z_2A_0603"
				(at 15.24 -5.08 0)
				(effects
					(font
						(size 1.27 1.27)
						(thickness 0.15)
					)
					(justify left bottom)
					(hide yes)
				)
			)
			(property "Footprint" "antmicro-footprints:FB_0603_1608Metric"
				(at 15.24 -7.62 0)
				(effects
					(font
						(size 1.27 1.27)
						(thickness 0.15)
					)
					(justify left bottom)
					(hide yes)
				)
			)
			(property "Datasheet" "https://www.murata.com/en-us/products/productdata/8796738650142/ENFA0003.pdf"
				(at 15.24 -10.16 0)
				(effects
					(font
						(size 1.27 1.27)
						(thickness 0.15)
					)
					(justify left bottom)
					(hide yes)
				)
			)
			(property "Description" "Ferrite Beads WE-TMSB Suppression 240Ohm 200mA"
				(at 0 0 0)
				(effects
					(font
						(size 1.27 1.27)
					)
					(hide yes)
				)
			)
			(property "MPN" "BLM18PG121SN1D"
				(at 15.24 -12.7 0)
				(effects
					(font
						(size 1.27 1.27)
						(thickness 0.15)
					)
					(justify left bottom)
				)
			)
			(property "Manufacturer" "Murata"
				(at 15.24 -15.24 0)
				(effects
					(font
						(size 1.27 1.27)
						(thickness 0.15)
					)
					(justify left bottom)
					(hide yes)
				)
			)
			(property "Val" "240"
				(at 20.32 -10.16 0)
				(effects
					(font
						(size 1.27 1.27)
						(thickness 0.15)
					)
					(justify left bottom)
				)
			)
			(property "Author" "Antmicro"
				(at 15.24 -17.78 0)
				(effects
					(font
						(size 1.27 1.27)
						(thickness 0.15)
					)
					(justify left bottom)
					(hide yes)
				)
			)
			(property "Current" "0.2A"
				(at 20.32 -22.86 0)
				(effects
					(font
						(size 1.27 1.27)
						(thickness 0.15)
					)
					(justify left bottom)
					(hide yes)
				)
			)
			(property "License" "Apache-2.0"
				(at 15.24 -20.32 0)
				(effects
					(font
						(size 1.27 1.27)
						(thickness 0.15)
					)
					(justify left bottom)
					(hide yes)
				)
			)
			(property "ki_keywords" " Multilayer Suppression Beads "
				(at 0 0 0)
				(effects
					(font
						(size 1.27 1.27)
					)
					(hide yes)
				)
			)
			(symbol "FB_120Z_2A_Murata-BLM18PG_0603_0_1"
				(polyline
					(pts
						(xy 1.651 0) (xy 1.2446 0)
					)
					(stroke
						(width 0)
						(type default)
					)
					(fill
						(type none)
					)
				)
				(polyline
					(pts
						(xy 2.2606 -1.8288) (xy 1.0414 -1.1176) (xy 2.7432 1.8288) (xy 3.9624 1.1176) (xy 2.2606 -1.8288)
					)
					(stroke
						(width 0)
						(type default)
					)
					(fill
						(type none)
					)
				)
				(polyline
					(pts
						(xy 3.81 0) (xy 3.3274 0)
					)
					(stroke
						(width 0)
						(type default)
					)
					(fill
						(type none)
					)
				)
			)
			(symbol "FB_120Z_2A_Murata-BLM18PG_0603_1_1"
				(pin passive line
					(at 0 0 0)
					(length 1.27)
					(name "~"
						(effects
							(font
								(size 1.27 1.27)
							)
						)
					)
					(number "1"
						(effects
							(font
								(size 1.27 1.27)
							)
						)
					)
				)
				(pin passive line
					(at 5.08 0 180)
					(length 1.27)
					(name "~"
						(effects
							(font
								(size 1.27 1.27)
							)
						)
					)
					(number "2"
						(effects
							(font
								(size 1.27 1.27)
							)
						)
					)
				)
			)
		)
	(symbol "antmicroFerriteBeadsandChips:FB_600Z_0.5A_Murata-BLM18AG_0603"
			(pin_numbers
				(hide yes)
			)
			(pin_names
				(hide yes)
			)
			(exclude_from_sim no)
			(in_bom yes)
			(on_board yes)
			(property "Reference" "FB"
				(at 15.24 -2.54 0)
				(effects
					(font
						(size 1.27 1.27)
						(thickness 0.15)
					)
					(justify left bottom)
				)
			)
			(property "Value" "FB_600Z_0.5A_0603"
				(at 15.24 -5.08 0)
				(effects
					(font
						(size 1.27 1.27)
						(thickness 0.15)
					)
					(justify left bottom)
					(hide yes)
				)
			)
			(property "Footprint" "antmicro-footprints:FB_0603_1608Metric"
				(at 15.24 -7.62 0)
				(effects
					(font
						(size 1.27 1.27)
						(thickness 0.15)
					)
					(justify left bottom)
					(hide yes)
				)
			)
			(property "Datasheet" "https://www.murata.com/en-us/products/productdata/8796738650142/ENFA0003.pdf"
				(at 15.24 -10.16 0)
				(effects
					(font
						(size 1.27 1.27)
						(thickness 0.15)
					)
					(justify left bottom)
					(hide yes)
				)
			)
			(property "Description" "Ferrite Beads WE-TMSB Suppression 240Ohm 200mA"
				(at 0 0 0)
				(effects
					(font
						(size 1.27 1.27)
					)
					(hide yes)
				)
			)
			(property "MPN" "BLM18AG601SN1D"
				(at 15.24 -12.7 0)
				(effects
					(font
						(size 1.27 1.27)
						(thickness 0.15)
					)
					(justify left bottom)
				)
			)
			(property "Manufacturer" "Murata"
				(at 15.24 -15.24 0)
				(effects
					(font
						(size 1.27 1.27)
						(thickness 0.15)
					)
					(justify left bottom)
					(hide yes)
				)
			)
			(property "Val" "240"
				(at 20.32 -10.16 0)
				(effects
					(font
						(size 1.27 1.27)
						(thickness 0.15)
					)
					(justify left bottom)
				)
			)
			(property "Author" "Antmicro"
				(at 15.24 -17.78 0)
				(effects
					(font
						(size 1.27 1.27)
						(thickness 0.15)
					)
					(justify left bottom)
					(hide yes)
				)
			)
			(property "Current" "0.2A"
				(at 20.32 -22.86 0)
				(effects
					(font
						(size 1.27 1.27)
						(thickness 0.15)
					)
					(justify left bottom)
					(hide yes)
				)
			)
			(property "License" "Apache-2.0"
				(at 15.24 -20.32 0)
				(effects
					(font
						(size 1.27 1.27)
						(thickness 0.15)
					)
					(justify left bottom)
					(hide yes)
				)
			)
			(property "ki_keywords" " Multilayer Suppression Beads "
				(at 0 0 0)
				(effects
					(font
						(size 1.27 1.27)
					)
					(hide yes)
				)
			)
			(symbol "FB_600Z_0.5A_Murata-BLM18AG_0603_0_1"
				(polyline
					(pts
						(xy 1.651 0) (xy 1.2446 0)
					)
					(stroke
						(width 0)
						(type default)
					)
					(fill
						(type none)
					)
				)
				(polyline
					(pts
						(xy 2.2606 -1.8288) (xy 1.0414 -1.1176) (xy 2.7432 1.8288) (xy 3.9624 1.1176) (xy 2.2606 -1.8288)
					)
					(stroke
						(width 0)
						(type default)
					)
					(fill
						(type none)
					)
				)
				(polyline
					(pts
						(xy 3.81 0) (xy 3.3274 0)
					)
					(stroke
						(width 0)
						(type default)
					)
					(fill
						(type none)
					)
				)
			)
			(symbol "FB_600Z_0.5A_Murata-BLM18AG_0603_1_1"
				(pin passive line
					(at 0 0 0)
					(length 1.27)
					(name "~"
						(effects
							(font
								(size 1.27 1.27)
							)
						)
					)
					(number "1"
						(effects
							(font
								(size 1.27 1.27)
							)
						)
					)
				)
				(pin passive line
					(at 5.08 0 180)
					(length 1.27)
					(name "~"
						(effects
							(font
								(size 1.27 1.27)
							)
						)
					)
					(number "2"
						(effects
							(font
								(size 1.27 1.27)
							)
						)
					)
				)
			)
		)
	(symbol "antmicroFixedInductors:L_470n_3.4A_WE-MAIA-2512"
			(pin_numbers
				(hide yes)
			)
			(pin_names
				(hide yes)
			)
			(exclude_from_sim no)
			(in_bom yes)
			(on_board yes)
			(property "Reference" "L"
				(at 13.97 0 0)
				(effects
					(font
						(size 1.27 1.27)
						(thickness 0.15)
					)
					(justify left bottom)
				)
			)
			(property "Value" "L_470n_3.4A_WE-MAIA-2512"
				(at 13.97 -2.54 0)
				(effects
					(font
						(size 1.27 1.27)
						(thickness 0.15)
					)
					(justify left bottom)
					(hide yes)
				)
			)
			(property "Footprint" "antmicro-footprints:L_WE-MAIA-2512"
				(at 13.97 -7.62 0)
				(effects
					(font
						(size 1.27 1.27)
						(thickness 0.15)
					)
					(justify left bottom)
					(hide yes)
				)
			)
			(property "Datasheet" "https://www.we-online.com/catalog/datasheet/784383240047.pdf"
				(at 13.97 -10.16 0)
				(effects
					(font
						(size 1.27 1.27)
						(thickness 0.15)
					)
					(justify left bottom)
					(hide yes)
				)
			)
			(property "Description" "Power Inductor (SMT), AEC-Q200, 470 nH, 3.4 A, Shielded, 6.25 A, WE-MAIA"
				(at 0 0 0)
				(effects
					(font
						(size 1.27 1.27)
					)
					(hide yes)
				)
			)
			(property "Val" "470n/3.4A"
				(at 13.97 -5.08 0)
				(effects
					(font
						(size 1.27 1.27)
						(thickness 0.15)
					)
					(justify left bottom)
				)
			)
			(property "Manufacturer" "Würth Elektronik"
				(at 13.97 -12.7 0)
				(effects
					(font
						(size 1.27 1.27)
						(thickness 0.15)
					)
					(justify left bottom)
					(hide yes)
				)
			)
			(property "MPN" "784383240047"
				(at 13.97 -15.24 0)
				(effects
					(font
						(size 1.27 1.27)
						(thickness 0.15)
					)
					(justify left bottom)
					(hide yes)
				)
			)
			(property "ISat" "6.25 A"
				(at 13.97 -16.51 0)
				(effects
					(font
						(size 1.27 1.27)
					)
					(justify left)
					(hide yes)
				)
			)
			(property "IMax" "3.4 A"
				(at 13.97 -20.32 0)
				(effects
					(font
						(size 1.27 1.27)
						(thickness 0.15)
					)
					(justify left bottom)
					(hide yes)
				)
			)
			(property "Size" "2x2.5"
				(at 13.97 -22.86 0)
				(effects
					(font
						(size 1.27 1.27)
						(thickness 0.15)
					)
					(justify left bottom)
					(hide yes)
				)
			)
			(property "Author" "Antmicro"
				(at 13.97 -25.4 0)
				(effects
					(font
						(size 1.27 1.27)
						(thickness 0.15)
					)
					(justify left bottom)
					(hide yes)
				)
			)
			(property "License" "Apache-2.0"
				(at 13.97 -27.94 0)
				(effects
					(font
						(size 1.27 1.27)
						(thickness 0.15)
					)
					(justify left bottom)
					(hide yes)
				)
			)
			(property "ki_keywords" "SMT, INDUCTOR, PASSIVE"
				(at 0 0 0)
				(effects
					(font
						(size 1.27 1.27)
					)
					(hide yes)
				)
			)
			(symbol "L_470n_3.4A_WE-MAIA-2512_0_1"
				(arc
					(start 0.508 0)
					(mid 1.016 0.5058)
					(end 1.524 0)
					(stroke
						(width 0)
						(type default)
					)
					(fill
						(type none)
					)
				)
				(arc
					(start 1.524 0)
					(mid 2.032 0.5058)
					(end 2.54 0)
					(stroke
						(width 0)
						(type default)
					)
					(fill
						(type none)
					)
				)
				(arc
					(start 2.54 0)
					(mid 3.048 0.5058)
					(end 3.556 0)
					(stroke
						(width 0)
						(type default)
					)
					(fill
						(type none)
					)
				)
				(arc
					(start 3.556 0)
					(mid 4.064 0.5058)
					(end 4.572 0)
					(stroke
						(width 0)
						(type default)
					)
					(fill
						(type none)
					)
				)
			)
			(symbol "L_470n_3.4A_WE-MAIA-2512_1_1"
				(pin passive line
					(at 0 0 0)
					(length 0.508)
					(name "~"
						(effects
							(font
								(size 1.27 1.27)
							)
						)
					)
					(number "1"
						(effects
							(font
								(size 1.27 1.27)
							)
						)
					)
				)
				(pin passive line
					(at 5.08 0 180)
					(length 0.508)
					(name "~"
						(effects
							(font
								(size 1.27 1.27)
							)
						)
					)
					(number "2"
						(effects
							(font
								(size 1.27 1.27)
							)
						)
					)
				)
			)
		)
	(symbol "antmicroFixedInductors:L_470n_4.6A_WE-MAIA-3015"
			(pin_numbers
				(hide yes)
			)
			(pin_names
				(hide yes)
			)
			(exclude_from_sim no)
			(in_bom yes)
			(on_board yes)
			(property "Reference" "L"
				(at 13.97 0 0)
				(effects
					(font
						(size 1.27 1.27)
						(thickness 0.15)
					)
					(justify left bottom)
				)
			)
			(property "Value" "L_470n_4.6A_WE-MAIA-3015"
				(at 13.97 -2.54 0)
				(effects
					(font
						(size 1.27 1.27)
						(thickness 0.15)
					)
					(justify left bottom)
					(hide yes)
				)
			)
			(property "Footprint" "antmicro-footprints:L_WE-MAIA-3015"
				(at 13.97 -7.62 0)
				(effects
					(font
						(size 1.27 1.27)
						(thickness 0.15)
					)
					(justify left bottom)
					(hide yes)
				)
			)
			(property "Datasheet" "https://www.we-online.com/catalog/datasheet/784383350047.pdf"
				(at 13.97 -10.16 0)
				(effects
					(font
						(size 1.27 1.27)
						(thickness 0.15)
					)
					(justify left bottom)
					(hide yes)
				)
			)
			(property "Description" "Power Inductor (SMT), AEC-Q200, 470 nH, 4.6 A, Shielded, 5.8 A, WE-MAIA"
				(at 0 0 0)
				(effects
					(font
						(size 1.27 1.27)
					)
					(hide yes)
				)
			)
			(property "Val" "470n/4.6A"
				(at 13.97 -5.08 0)
				(effects
					(font
						(size 1.27 1.27)
						(thickness 0.15)
					)
					(justify left bottom)
				)
			)
			(property "Manufacturer" "Würth Elektronik"
				(at 13.97 -12.7 0)
				(effects
					(font
						(size 1.27 1.27)
						(thickness 0.15)
					)
					(justify left bottom)
					(hide yes)
				)
			)
			(property "MPN" "784383350047"
				(at 13.97 -15.24 0)
				(effects
					(font
						(size 1.27 1.27)
						(thickness 0.15)
					)
					(justify left bottom)
					(hide yes)
				)
			)
			(property "ISat" "5.8 A"
				(at 13.97 -16.51 0)
				(effects
					(font
						(size 1.27 1.27)
					)
					(justify left)
					(hide yes)
				)
			)
			(property "IMax" "4.6 A"
				(at 13.97 -20.32 0)
				(effects
					(font
						(size 1.27 1.27)
						(thickness 0.15)
					)
					(justify left bottom)
					(hide yes)
				)
			)
			(property "Size" "3.0x3.0"
				(at 13.97 -22.86 0)
				(effects
					(font
						(size 1.27 1.27)
						(thickness 0.15)
					)
					(justify left bottom)
					(hide yes)
				)
			)
			(property "Author" "Antmicro"
				(at 13.97 -25.4 0)
				(effects
					(font
						(size 1.27 1.27)
						(thickness 0.15)
					)
					(justify left bottom)
					(hide yes)
				)
			)
			(property "License" "Apache-2.0"
				(at 13.97 -27.94 0)
				(effects
					(font
						(size 1.27 1.27)
						(thickness 0.15)
					)
					(justify left bottom)
					(hide yes)
				)
			)
			(property "ki_keywords" "SMT, INDUCTOR, PASSIVE"
				(at 0 0 0)
				(effects
					(font
						(size 1.27 1.27)
					)
					(hide yes)
				)
			)
			(symbol "L_470n_4.6A_WE-MAIA-3015_0_1"
				(arc
					(start 0.508 0)
					(mid 1.016 0.5058)
					(end 1.524 0)
					(stroke
						(width 0)
						(type default)
					)
					(fill
						(type none)
					)
				)
				(arc
					(start 1.524 0)
					(mid 2.032 0.5058)
					(end 2.54 0)
					(stroke
						(width 0)
						(type default)
					)
					(fill
						(type none)
					)
				)
				(arc
					(start 2.54 0)
					(mid 3.048 0.5058)
					(end 3.556 0)
					(stroke
						(width 0)
						(type default)
					)
					(fill
						(type none)
					)
				)
				(arc
					(start 3.556 0)
					(mid 4.064 0.5058)
					(end 4.572 0)
					(stroke
						(width 0)
						(type default)
					)
					(fill
						(type none)
					)
				)
			)
			(symbol "L_470n_4.6A_WE-MAIA-3015_1_1"
				(pin passive line
					(at 0 0 0)
					(length 0.508)
					(name "~"
						(effects
							(font
								(size 1.27 1.27)
							)
						)
					)
					(number "1"
						(effects
							(font
								(size 1.27 1.27)
							)
						)
					)
				)
				(pin passive line
					(at 5.08 0 180)
					(length 0.508)
					(name "~"
						(effects
							(font
								(size 1.27 1.27)
							)
						)
					)
					(number "2"
						(effects
							(font
								(size 1.27 1.27)
							)
						)
					)
				)
			)
		)
	(symbol "antmicroFixedInductors:L_4u7_2.8A_2020"
			(pin_numbers
				(hide yes)
			)
			(pin_names
				(hide yes)
			)
			(exclude_from_sim no)
			(in_bom yes)
			(on_board yes)
			(property "Reference" "L"
				(at 13.97 0 0)
				(effects
					(font
						(size 1.27 1.27)
						(thickness 0.15)
					)
					(justify left bottom)
				)
			)
			(property "Value" "L_4u7_2.8A_2020"
				(at 13.97 -2.54 0)
				(effects
					(font
						(size 1.27 1.27)
						(thickness 0.15)
					)
					(justify left bottom)
					(hide yes)
				)
			)
			(property "Footprint" "antmicro-footprints:L_2020_5252Metric"
				(at 13.97 -7.62 0)
				(effects
					(font
						(size 1.27 1.27)
						(thickness 0.15)
					)
					(justify left bottom)
					(hide yes)
				)
			)
			(property "Datasheet" ""
				(at 13.97 -10.16 0)
				(effects
					(font
						(size 1.27 1.27)
						(thickness 0.15)
					)
					(justify left bottom)
					(hide yes)
				)
			)
			(property "Description" ""
				(at 0 0 0)
				(effects
					(font
						(size 1.27 1.27)
					)
					(hide yes)
				)
			)
			(property "Val" "4u7/2.8A"
				(at 13.97 -5.08 0)
				(effects
					(font
						(size 1.27 1.27)
						(thickness 0.15)
					)
					(justify left bottom)
				)
			)
			(property "Manufacturer" "Vishay"
				(at 13.97 -12.7 0)
				(effects
					(font
						(size 1.27 1.27)
						(thickness 0.15)
					)
					(justify left bottom)
					(hide yes)
				)
			)
			(property "MPN" "IHLP2020BZER4R7M01"
				(at 13.97 -15.24 0)
				(effects
					(font
						(size 1.27 1.27)
						(thickness 0.15)
					)
					(justify left bottom)
					(hide yes)
				)
			)
			(property "ISat" ""
				(at 13.97 -16.51 0)
				(effects
					(font
						(size 1.27 1.27)
					)
					(justify left)
					(hide yes)
				)
			)
			(property "IMax" ""
				(at 13.97 -20.32 0)
				(effects
					(font
						(size 1.27 1.27)
						(thickness 0.15)
					)
					(justify left bottom)
					(hide yes)
				)
			)
			(property "Size" "5.18x5.18"
				(at 13.97 -22.86 0)
				(effects
					(font
						(size 1.27 1.27)
						(thickness 0.15)
					)
					(justify left bottom)
					(hide yes)
				)
			)
			(property "Author" "Antmicro"
				(at 13.97 -25.4 0)
				(effects
					(font
						(size 1.27 1.27)
						(thickness 0.15)
					)
					(justify left bottom)
					(hide yes)
				)
			)
			(property "License" "Apache-2.0"
				(at 13.97 -27.94 0)
				(effects
					(font
						(size 1.27 1.27)
						(thickness 0.15)
					)
					(justify left bottom)
					(hide yes)
				)
			)
			(symbol "L_4u7_2.8A_2020_0_1"
				(arc
					(start 0.508 0)
					(mid 1.016 0.5058)
					(end 1.524 0)
					(stroke
						(width 0)
						(type default)
					)
					(fill
						(type none)
					)
				)
				(arc
					(start 1.524 0)
					(mid 2.032 0.5058)
					(end 2.54 0)
					(stroke
						(width 0)
						(type default)
					)
					(fill
						(type none)
					)
				)
				(arc
					(start 2.54 0)
					(mid 3.048 0.5058)
					(end 3.556 0)
					(stroke
						(width 0)
						(type default)
					)
					(fill
						(type none)
					)
				)
				(arc
					(start 3.556 0)
					(mid 4.064 0.5058)
					(end 4.572 0)
					(stroke
						(width 0)
						(type default)
					)
					(fill
						(type none)
					)
				)
			)
			(symbol "L_4u7_2.8A_2020_1_1"
				(pin passive line
					(at 0 0 0)
					(length 0.508)
					(name "~"
						(effects
							(font
								(size 1.27 1.27)
							)
						)
					)
					(number "1"
						(effects
							(font
								(size 1.27 1.27)
							)
						)
					)
				)
				(pin passive line
					(at 5.08 0 180)
					(length 0.508)
					(name "~"
						(effects
							(font
								(size 1.27 1.27)
							)
						)
					)
					(number "2"
						(effects
							(font
								(size 1.27 1.27)
							)
						)
					)
				)
			)
		)
	(symbol "antmicroFixedInductors:L_680n_4.4A_1210"
			(pin_numbers
				(hide yes)
			)
			(pin_names
				(hide yes)
			)
			(exclude_from_sim no)
			(in_bom yes)
			(on_board yes)
			(property "Reference" "L"
				(at 13.97 0 0)
				(effects
					(font
						(size 1.27 1.27)
						(thickness 0.15)
					)
					(justify left bottom)
				)
			)
			(property "Value" "L_680n_6.1A_1210"
				(at 13.97 -2.54 0)
				(effects
					(font
						(size 1.27 1.27)
						(thickness 0.15)
					)
					(justify left bottom)
					(hide yes)
				)
			)
			(property "Footprint" "antmicro-footprints:L_1210_3225Metric"
				(at 13.97 -7.62 0)
				(effects
					(font
						(size 1.27 1.27)
						(thickness 0.15)
					)
					(justify left bottom)
					(hide yes)
				)
			)
			(property "Datasheet" "https://www.murata.com/en-global/products/productdetail?partno=DFE322512F-R68M%23"
				(at 13.97 -10.16 0)
				(effects
					(font
						(size 1.27 1.27)
						(thickness 0.15)
					)
					(justify left bottom)
					(hide yes)
				)
			)
			(property "Description" ""
				(at 0 0 0)
				(effects
					(font
						(size 1.27 1.27)
					)
					(hide yes)
				)
			)
			(property "Val" "680n/6.1A"
				(at 13.97 -5.08 0)
				(effects
					(font
						(size 1.27 1.27)
						(thickness 0.15)
					)
					(justify left bottom)
				)
			)
			(property "Manufacturer" "Murata"
				(at 13.97 -12.7 0)
				(effects
					(font
						(size 1.27 1.27)
						(thickness 0.15)
					)
					(justify left bottom)
					(hide yes)
				)
			)
			(property "MPN" "DFE322512F-R68M=P2"
				(at 13.97 -15.24 0)
				(effects
					(font
						(size 1.27 1.27)
						(thickness 0.15)
					)
					(justify left bottom)
					(hide yes)
				)
			)
			(property "ISat" ""
				(at 13.97 -16.51 0)
				(effects
					(font
						(size 1.27 1.27)
					)
					(justify left)
					(hide yes)
				)
			)
			(property "IMax" ""
				(at 13.97 -20.32 0)
				(effects
					(font
						(size 1.27 1.27)
						(thickness 0.15)
					)
					(justify left bottom)
					(hide yes)
				)
			)
			(property "Size" "3.2x2.5"
				(at 13.97 -22.86 0)
				(effects
					(font
						(size 1.27 1.27)
						(thickness 0.15)
					)
					(justify left bottom)
					(hide yes)
				)
			)
			(property "Author" "Antmicro"
				(at 13.97 -25.4 0)
				(effects
					(font
						(size 1.27 1.27)
						(thickness 0.15)
					)
					(justify left bottom)
					(hide yes)
				)
			)
			(property "License" "Apache-2.0"
				(at 13.97 -27.94 0)
				(effects
					(font
						(size 1.27 1.27)
						(thickness 0.15)
					)
					(justify left bottom)
					(hide yes)
				)
			)
			(symbol "L_680n_4.4A_1210_0_1"
				(arc
					(start 0.508 0)
					(mid 1.016 0.5058)
					(end 1.524 0)
					(stroke
						(width 0)
						(type default)
					)
					(fill
						(type none)
					)
				)
				(arc
					(start 1.524 0)
					(mid 2.032 0.5058)
					(end 2.54 0)
					(stroke
						(width 0)
						(type default)
					)
					(fill
						(type none)
					)
				)
				(arc
					(start 2.54 0)
					(mid 3.048 0.5058)
					(end 3.556 0)
					(stroke
						(width 0)
						(type default)
					)
					(fill
						(type none)
					)
				)
				(arc
					(start 3.556 0)
					(mid 4.064 0.5058)
					(end 4.572 0)
					(stroke
						(width 0)
						(type default)
					)
					(fill
						(type none)
					)
				)
			)
			(symbol "L_680n_4.4A_1210_1_1"
				(pin passive line
					(at 0 0 0)
					(length 0.508)
					(name "~"
						(effects
							(font
								(size 1.27 1.27)
							)
						)
					)
					(number "1"
						(effects
							(font
								(size 1.27 1.27)
							)
						)
					)
				)
				(pin passive line
					(at 5.08 0 180)
					(length 0.508)
					(name "~"
						(effects
							(font
								(size 1.27 1.27)
							)
						)
					)
					(number "2"
						(effects
							(font
								(size 1.27 1.27)
							)
						)
					)
				)
			)
		)
	(symbol "antmicroFixedInductors:L_7u2_7.9A_WE-PDF-1064"
			(pin_numbers
				(hide yes)
			)
			(pin_names
				(hide yes)
			)
			(exclude_from_sim no)
			(in_bom yes)
			(on_board yes)
			(property "Reference" "L"
				(at 13.97 0 0)
				(effects
					(font
						(size 1.27 1.27)
						(thickness 0.15)
					)
					(justify left bottom)
				)
			)
			(property "Value" "L_7u2_7.9A_WE-PDF"
				(at 13.97 -2.54 0)
				(effects
					(font
						(size 1.27 1.27)
						(thickness 0.15)
					)
					(justify left bottom)
					(hide yes)
				)
			)
			(property "Footprint" "antmicro-footprints:L_WE-PDF-1064"
				(at 13.97 -7.62 0)
				(effects
					(font
						(size 1.27 1.27)
						(thickness 0.15)
					)
					(justify left bottom)
					(hide yes)
				)
			)
			(property "Datasheet" "https://www.we-online.com/catalog/datasheet/7447798720.pdf"
				(at 13.97 -10.16 0)
				(effects
					(font
						(size 1.27 1.27)
						(thickness 0.15)
					)
					(justify left bottom)
					(hide yes)
				)
			)
			(property "Description" ""
				(at 0 0 0)
				(effects
					(font
						(size 1.27 1.27)
					)
					(hide yes)
				)
			)
			(property "Val" "7u2/7.9A"
				(at 13.97 -5.08 0)
				(effects
					(font
						(size 1.27 1.27)
						(thickness 0.15)
					)
					(justify left bottom)
				)
			)
			(property "Manufacturer" "Würth Elektronik"
				(at 13.97 -12.7 0)
				(effects
					(font
						(size 1.27 1.27)
						(thickness 0.15)
					)
					(justify left bottom)
					(hide yes)
				)
			)
			(property "MPN" "7447798720"
				(at 13.97 -15.24 0)
				(effects
					(font
						(size 1.27 1.27)
						(thickness 0.15)
					)
					(justify left bottom)
					(hide yes)
				)
			)
			(property "ISat" ""
				(at 13.97 -16.51 0)
				(effects
					(font
						(size 1.27 1.27)
					)
					(justify left)
					(hide yes)
				)
			)
			(property "IMax" ""
				(at 13.97 -20.32 0)
				(effects
					(font
						(size 1.27 1.27)
						(thickness 0.15)
					)
					(justify left bottom)
					(hide yes)
				)
			)
			(property "Size" "10.2x10.2"
				(at 13.97 -22.86 0)
				(effects
					(font
						(size 1.27 1.27)
						(thickness 0.15)
					)
					(justify left bottom)
					(hide yes)
				)
			)
			(property "Author" "Antmicro"
				(at 13.97 -25.4 0)
				(effects
					(font
						(size 1.27 1.27)
						(thickness 0.15)
					)
					(justify left bottom)
					(hide yes)
				)
			)
			(property "License" "Apache-2.0"
				(at 13.97 -27.94 0)
				(effects
					(font
						(size 1.27 1.27)
						(thickness 0.15)
					)
					(justify left bottom)
					(hide yes)
				)
			)
			(symbol "L_7u2_7.9A_WE-PDF-1064_0_1"
				(arc
					(start 0.508 0)
					(mid 1.016 0.5058)
					(end 1.524 0)
					(stroke
						(width 0)
						(type default)
					)
					(fill
						(type none)
					)
				)
				(arc
					(start 1.524 0)
					(mid 2.032 0.5058)
					(end 2.54 0)
					(stroke
						(width 0)
						(type default)
					)
					(fill
						(type none)
					)
				)
				(arc
					(start 2.54 0)
					(mid 3.048 0.5058)
					(end 3.556 0)
					(stroke
						(width 0)
						(type default)
					)
					(fill
						(type none)
					)
				)
				(arc
					(start 3.556 0)
					(mid 4.064 0.5058)
					(end 4.572 0)
					(stroke
						(width 0)
						(type default)
					)
					(fill
						(type none)
					)
				)
			)
			(symbol "L_7u2_7.9A_WE-PDF-1064_1_1"
				(pin passive line
					(at 0 0 0)
					(length 0.508)
					(name "~"
						(effects
							(font
								(size 1.27 1.27)
							)
						)
					)
					(number "1"
						(effects
							(font
								(size 1.27 1.27)
							)
						)
					)
				)
				(pin passive line
					(at 5.08 0 180)
					(length 0.508)
					(name "~"
						(effects
							(font
								(size 1.27 1.27)
							)
						)
					)
					(number "2"
						(effects
							(font
								(size 1.27 1.27)
							)
						)
					)
				)
			)
		)
	(symbol "antmicroGenericPinHeaders:PinHeader_1x3_P2.54mm_Drill1.1mm"
			(exclude_from_sim no)
			(in_bom yes)
			(on_board yes)
			(property "Reference" "J"
				(at 20.32 -5.08 0)
				(effects
					(font
						(size 1.27 1.27)
						(thickness 0.15)
					)
					(justify left bottom)
				)
			)
			(property "Value" "PinHeader_1x3_P2.54mm_Drill1.1mm"
				(at 20.32 -10.16 0)
				(effects
					(font
						(size 1.27 1.27)
						(thickness 0.15)
					)
					(justify left bottom)
					(hide yes)
				)
			)
			(property "Footprint" "antmicro-footprints:PinHeader_1x3_P2.54mm_Drill1.1mm"
				(at 20.32 -12.7 0)
				(effects
					(font
						(size 1.27 1.27)
						(thickness 0.15)
					)
					(justify left bottom)
					(hide yes)
				)
			)
			(property "Datasheet" "https://katalog.we-online.de/em/datasheet/6130xx11121.pdf"
				(at 20.32 -15.24 0)
				(effects
					(font
						(size 1.27 1.27)
						(thickness 0.15)
					)
					(justify left bottom)
					(hide yes)
				)
			)
			(property "Description" "Pin Header, Vertical, Board-to-Board, 2.54 mm, 1 Rows, 3 Contacts, Through Hole Straight, WR-PHD"
				(at 0 0 0)
				(effects
					(font
						(size 1.27 1.27)
					)
					(hide yes)
				)
			)
			(property "MPN" "61300311121"
				(at 20.32 -7.62 0)
				(effects
					(font
						(size 1.27 1.27)
						(thickness 0.15)
					)
					(justify left bottom)
				)
			)
			(property "Manufacturer" "Würth Elektronik"
				(at 20.32 -17.78 0)
				(effects
					(font
						(size 1.27 1.27)
						(thickness 0.15)
					)
					(justify left bottom)
					(hide yes)
				)
			)
			(property "VSD_class" "IO Header"
				(at 20.32 -20.32 0)
				(effects
					(font
						(size 1.27 1.27)
						(thickness 0.15)
					)
					(justify left bottom)
					(hide yes)
				)
			)
			(property "Author" "Antmicro"
				(at 20.32 -22.86 0)
				(effects
					(font
						(size 1.27 1.27)
						(thickness 0.15)
					)
					(justify left bottom)
					(hide yes)
				)
			)
			(property "License" "Apache-2.0"
				(at 20.32 -25.4 0)
				(effects
					(font
						(size 1.27 1.27)
						(thickness 0.15)
					)
					(justify left bottom)
					(hide yes)
				)
			)
			(property "ki_keywords" "VERTICAL, THT, HEADER, CONNECTOR, MALE"
				(at 0 0 0)
				(effects
					(font
						(size 1.27 1.27)
					)
					(hide yes)
				)
			)
			(symbol "PinHeader_1x3_P2.54mm_Drill1.1mm_1_1"
				(rectangle
					(start 4.191 -0.254)
					(end 3.683 0.254)
					(stroke
						(width 0.254)
						(type default)
					)
					(fill
						(type none)
					)
				)
				(rectangle
					(start 4.191 -2.794)
					(end 3.683 -2.286)
					(stroke
						(width 0.254)
						(type default)
					)
					(fill
						(type none)
					)
				)
				(rectangle
					(start 4.191 -5.334)
					(end 3.683 -4.826)
					(stroke
						(width 0.254)
						(type default)
					)
					(fill
						(type none)
					)
				)
				(rectangle
					(start 5.08 -6.35)
					(end 2.54 1.27)
					(stroke
						(width 0.254)
						(type default)
					)
					(fill
						(type background)
					)
				)
				(pin passive line
					(at 0 0 0)
					(length 2.54)
					(name "~"
						(effects
							(font
								(size 1.27 1.27)
							)
						)
					)
					(number "1"
						(effects
							(font
								(size 1.27 1.27)
							)
						)
					)
				)
				(pin passive line
					(at 0 -2.54 0)
					(length 2.54)
					(name "~"
						(effects
							(font
								(size 1.27 1.27)
							)
						)
					)
					(number "2"
						(effects
							(font
								(size 1.27 1.27)
							)
						)
					)
				)
				(pin passive line
					(at 0 -5.08 0)
					(length 2.54)
					(name "~"
						(effects
							(font
								(size 1.27 1.27)
							)
						)
					)
					(number "3"
						(effects
							(font
								(size 1.27 1.27)
							)
						)
					)
				)
			)
		)
	(symbol "antmicroGenericPinHeaders:PinHeader_1x3_P2.54mm_Drill1.1mm_Horizontal"
			(exclude_from_sim no)
			(in_bom yes)
			(on_board yes)
			(property "Reference" "J"
				(at 20.32 -5.08 0)
				(effects
					(font
						(size 1.27 1.27)
						(thickness 0.15)
					)
					(justify left bottom)
				)
			)
			(property "Value" "PinHeader_1x3_P2.54mm_Drill1.1mm_Horizontal"
				(at 20.32 -7.62 0)
				(effects
					(font
						(size 1.27 1.27)
						(thickness 0.15)
					)
					(justify left bottom)
				)
			)
			(property "Footprint" "antmicro-footprints:PinHeader_1x3_P2.54mm_Horizontal"
				(at 20.32 -10.16 0)
				(effects
					(font
						(size 1.27 1.27)
						(thickness 0.15)
					)
					(justify left bottom)
					(hide yes)
				)
			)
			(property "Datasheet" "https://www.we-online.com/components/products/datasheet/6130xx11021.pdf"
				(at 20.32 -12.7 0)
				(effects
					(font
						(size 1.27 1.27)
						(thickness 0.15)
					)
					(justify left bottom)
					(hide yes)
				)
			)
			(property "Description" "Connector Header Through Hole, Right Angle 3 position 0.100\" (2.54mm)"
				(at 0 0 0)
				(effects
					(font
						(size 1.27 1.27)
					)
					(hide yes)
				)
			)
			(property "MPN" "61300311021"
				(at 20.32 -15.24 0)
				(effects
					(font
						(size 1.27 1.27)
						(thickness 0.15)
					)
					(justify left bottom)
					(hide yes)
				)
			)
			(property "Manufacturer" "Würth Elektronik"
				(at 20.32 -17.78 0)
				(effects
					(font
						(size 1.27 1.27)
						(thickness 0.15)
					)
					(justify left bottom)
					(hide yes)
				)
			)
			(property "Author" "Antmicro"
				(at 20.32 -20.32 0)
				(effects
					(font
						(size 1.27 1.27)
						(thickness 0.15)
					)
					(justify left bottom)
					(hide yes)
				)
			)
			(property "License" "Apache-2.0"
				(at 20.32 -22.86 0)
				(effects
					(font
						(size 1.27 1.27)
						(thickness 0.15)
					)
					(justify left bottom)
					(hide yes)
				)
			)
			(property "ki_keywords" "PINSTRIP, HEADER "
				(at 0 0 0)
				(effects
					(font
						(size 1.27 1.27)
					)
					(hide yes)
				)
			)
			(symbol "PinHeader_1x3_P2.54mm_Drill1.1mm_Horizontal_1_1"
				(rectangle
					(start 2.54 1.27)
					(end 5.334 -6.35)
					(stroke
						(width 0)
						(type default)
					)
					(fill
						(type background)
					)
				)
				(rectangle
					(start 4.191 -0.254)
					(end 3.683 0.254)
					(stroke
						(width 0.254)
						(type default)
					)
					(fill
						(type outline)
					)
				)
				(rectangle
					(start 4.191 -2.794)
					(end 3.683 -2.286)
					(stroke
						(width 0.254)
						(type default)
					)
					(fill
						(type outline)
					)
				)
				(rectangle
					(start 4.191 -5.334)
					(end 3.683 -4.826)
					(stroke
						(width 0.254)
						(type default)
					)
					(fill
						(type outline)
					)
				)
				(pin passive line
					(at 0 0 0)
					(length 2.54)
					(name "~"
						(effects
							(font
								(size 1.27 1.27)
							)
						)
					)
					(number "1"
						(effects
							(font
								(size 1.27 1.27)
							)
						)
					)
				)
				(pin passive line
					(at 0 -2.54 0)
					(length 2.54)
					(name "~"
						(effects
							(font
								(size 1.27 1.27)
							)
						)
					)
					(number "2"
						(effects
							(font
								(size 1.27 1.27)
							)
						)
					)
				)
				(pin passive line
					(at 0 -5.08 0)
					(length 2.54)
					(name "~"
						(effects
							(font
								(size 1.27 1.27)
							)
						)
					)
					(number "3"
						(effects
							(font
								(size 1.27 1.27)
							)
						)
					)
				)
			)
		)
	(symbol "antmicroGenericPinHeaders:PinHeader_2x7_P2mm_Drill0.9mm_878311420"
			(exclude_from_sim no)
			(in_bom yes)
			(on_board yes)
			(property "Reference" "J"
				(at 25.4 -2.54 0)
				(effects
					(font
						(size 1.27 1.27)
						(thickness 0.15)
					)
					(justify left bottom)
				)
			)
			(property "Value" "PinHeader_2x7_P2mm_Drill0.9mm_878311420"
				(at 25.4 -5.08 0)
				(effects
					(font
						(size 1.27 1.27)
						(thickness 0.15)
					)
					(justify left bottom)
					(hide yes)
				)
			)
			(property "Footprint" "antmicro-footprints:PinHeader_2x7_P2mm_Drill0.9mm_878311420"
				(at 25.4 -7.62 0)
				(effects
					(font
						(size 1.27 1.27)
						(thickness 0.15)
					)
					(justify left bottom)
					(hide yes)
				)
			)
			(property "Datasheet" "https://www.molex.com/en-us/products/part-detail-pdf/878311420?display=pdf"
				(at 25.4 -10.16 0)
				(effects
					(font
						(size 1.27 1.27)
						(thickness 0.15)
					)
					(justify left bottom)
					(hide yes)
				)
			)
			(property "Description" "2.00mm Pitch, Milli-Grid PCB Header, Dual Row, Vertical, Through Hole, Shrouded, 14 Circuits, 0.38µm Gold (Au) Plating, with Center Polarization Slot, with Locking Window, without PCB Locator, Tube"
				(at 25.4 -22.86 0)
				(effects
					(font
						(size 1.27 1.27)
					)
					(justify left bottom)
					(hide yes)
				)
			)
			(property "MPN" "878311420"
				(at 25.4 -12.7 0)
				(effects
					(font
						(size 1.27 1.27)
						(thickness 0.15)
					)
					(justify left bottom)
				)
			)
			(property "Manufacturer" "Molex"
				(at 25.4 -15.24 0)
				(effects
					(font
						(size 1.27 1.27)
						(thickness 0.15)
					)
					(justify left bottom)
					(hide yes)
				)
			)
			(property "Author" "Antmicro"
				(at 25.4 -17.78 0)
				(effects
					(font
						(size 1.27 1.27)
						(thickness 0.15)
					)
					(justify left bottom)
					(hide yes)
				)
			)
			(property "License" "Apache-2.0"
				(at 25.4 -20.32 0)
				(effects
					(font
						(size 1.27 1.27)
						(thickness 0.15)
					)
					(justify left bottom)
					(hide yes)
				)
			)
			(property "ki_keywords" "PINSTRIP, HEADER "
				(at 0 0 0)
				(effects
					(font
						(size 1.27 1.27)
					)
					(hide yes)
				)
			)
			(symbol "PinHeader_2x7_P2mm_Drill0.9mm_878311420_1_1"
				(rectangle
					(start 2.54 1.27)
					(end 7.62 -16.51)
					(stroke
						(width 0.254)
						(type default)
					)
					(fill
						(type background)
					)
				)
				(rectangle
					(start 3.556 0.254)
					(end 4.064 -0.254)
					(stroke
						(width 0.254)
						(type default)
					)
					(fill
						(type background)
					)
				)
				(rectangle
					(start 3.556 -2.286)
					(end 4.064 -2.794)
					(stroke
						(width 0.254)
						(type default)
					)
					(fill
						(type background)
					)
				)
				(rectangle
					(start 3.556 -4.826)
					(end 4.064 -5.334)
					(stroke
						(width 0.254)
						(type default)
					)
					(fill
						(type background)
					)
				)
				(rectangle
					(start 3.556 -7.366)
					(end 4.064 -7.874)
					(stroke
						(width 0.254)
						(type default)
					)
					(fill
						(type background)
					)
				)
				(rectangle
					(start 3.556 -9.906)
					(end 4.064 -10.414)
					(stroke
						(width 0.254)
						(type default)
					)
					(fill
						(type background)
					)
				)
				(rectangle
					(start 3.556 -12.446)
					(end 4.064 -12.954)
					(stroke
						(width 0.254)
						(type default)
					)
					(fill
						(type background)
					)
				)
				(rectangle
					(start 3.556 -14.986)
					(end 4.064 -15.494)
					(stroke
						(width 0.254)
						(type default)
					)
					(fill
						(type background)
					)
				)
				(rectangle
					(start 6.096 0.254)
					(end 6.604 -0.254)
					(stroke
						(width 0.254)
						(type default)
					)
					(fill
						(type background)
					)
				)
				(rectangle
					(start 6.096 -2.286)
					(end 6.604 -2.794)
					(stroke
						(width 0.254)
						(type default)
					)
					(fill
						(type background)
					)
				)
				(rectangle
					(start 6.096 -4.826)
					(end 6.604 -5.334)
					(stroke
						(width 0.254)
						(type default)
					)
					(fill
						(type background)
					)
				)
				(rectangle
					(start 6.096 -7.366)
					(end 6.604 -7.874)
					(stroke
						(width 0.254)
						(type default)
					)
					(fill
						(type background)
					)
				)
				(rectangle
					(start 6.096 -9.906)
					(end 6.604 -10.414)
					(stroke
						(width 0.254)
						(type default)
					)
					(fill
						(type background)
					)
				)
				(rectangle
					(start 6.096 -12.446)
					(end 6.604 -12.954)
					(stroke
						(width 0.254)
						(type default)
					)
					(fill
						(type background)
					)
				)
				(rectangle
					(start 6.096 -14.986)
					(end 6.604 -15.494)
					(stroke
						(width 0.254)
						(type default)
					)
					(fill
						(type background)
					)
				)
				(pin passive line
					(at 0 0 0)
					(length 2.54)
					(name "~"
						(effects
							(font
								(size 1.27 1.27)
							)
						)
					)
					(number "1"
						(effects
							(font
								(size 1.27 1.27)
							)
						)
					)
				)
				(pin passive line
					(at 0 -2.54 0)
					(length 2.54)
					(name "~"
						(effects
							(font
								(size 1.27 1.27)
							)
						)
					)
					(number "3"
						(effects
							(font
								(size 1.27 1.27)
							)
						)
					)
				)
				(pin passive line
					(at 0 -5.08 0)
					(length 2.54)
					(name "~"
						(effects
							(font
								(size 1.27 1.27)
							)
						)
					)
					(number "5"
						(effects
							(font
								(size 1.27 1.27)
							)
						)
					)
				)
				(pin passive line
					(at 0 -7.62 0)
					(length 2.54)
					(name "~"
						(effects
							(font
								(size 1.27 1.27)
							)
						)
					)
					(number "7"
						(effects
							(font
								(size 1.27 1.27)
							)
						)
					)
				)
				(pin passive line
					(at 0 -10.16 0)
					(length 2.54)
					(name "~"
						(effects
							(font
								(size 1.27 1.27)
							)
						)
					)
					(number "9"
						(effects
							(font
								(size 1.27 1.27)
							)
						)
					)
				)
				(pin passive line
					(at 0 -12.7 0)
					(length 2.54)
					(name "~"
						(effects
							(font
								(size 1.27 1.27)
							)
						)
					)
					(number "11"
						(effects
							(font
								(size 1.27 1.27)
							)
						)
					)
				)
				(pin passive line
					(at 0 -15.24 0)
					(length 2.54)
					(name "~"
						(effects
							(font
								(size 1.27 1.27)
							)
						)
					)
					(number "13"
						(effects
							(font
								(size 1.27 1.27)
							)
						)
					)
				)
				(pin passive line
					(at 10.16 0 180)
					(length 2.54)
					(name "~"
						(effects
							(font
								(size 1.27 1.27)
							)
						)
					)
					(number "2"
						(effects
							(font
								(size 1.27 1.27)
							)
						)
					)
				)
				(pin passive line
					(at 10.16 -2.54 180)
					(length 2.54)
					(name "~"
						(effects
							(font
								(size 1.27 1.27)
							)
						)
					)
					(number "4"
						(effects
							(font
								(size 1.27 1.27)
							)
						)
					)
				)
				(pin passive line
					(at 10.16 -5.08 180)
					(length 2.54)
					(name "~"
						(effects
							(font
								(size 1.27 1.27)
							)
						)
					)
					(number "6"
						(effects
							(font
								(size 1.27 1.27)
							)
						)
					)
				)
				(pin passive line
					(at 10.16 -7.62 180)
					(length 2.54)
					(name "~"
						(effects
							(font
								(size 1.27 1.27)
							)
						)
					)
					(number "8"
						(effects
							(font
								(size 1.27 1.27)
							)
						)
					)
				)
				(pin passive line
					(at 10.16 -10.16 180)
					(length 2.54)
					(name "~"
						(effects
							(font
								(size 1.27 1.27)
							)
						)
					)
					(number "10"
						(effects
							(font
								(size 1.27 1.27)
							)
						)
					)
				)
				(pin passive line
					(at 10.16 -12.7 180)
					(length 2.54)
					(name "~"
						(effects
							(font
								(size 1.27 1.27)
							)
						)
					)
					(number "12"
						(effects
							(font
								(size 1.27 1.27)
							)
						)
					)
				)
				(pin passive line
					(at 10.16 -15.24 180)
					(length 2.54)
					(name "~"
						(effects
							(font
								(size 1.27 1.27)
							)
						)
					)
					(number "14"
						(effects
							(font
								(size 1.27 1.27)
							)
						)
					)
				)
			)
		)
	(symbol "antmicroInterfaceControllers:FT4232H_VQFN"
			(exclude_from_sim no)
			(in_bom yes)
			(on_board yes)
			(property "Reference" "U"
				(at 55.88 -2.54 0)
				(effects
					(font
						(size 1.27 1.27)
						(thickness 0.15)
					)
					(justify left bottom)
				)
			)
			(property "Value" "FT4232H_VQFN"
				(at 55.88 -5.08 0)
				(effects
					(font
						(size 1.27 1.27)
						(thickness 0.15)
					)
					(justify left bottom)
				)
			)
			(property "Footprint" "antmicro-footprints:QFN-56-1EP_8x8mm_P0.5mm"
				(at 55.88 -7.62 0)
				(effects
					(font
						(size 1.27 1.27)
						(thickness 0.15)
					)
					(justify left bottom)
					(hide yes)
				)
			)
			(property "Datasheet" "https://www.ftdichip.com/Support/Documents/DataSheets/ICs/DS_FT4232H.pdf"
				(at 55.88 -10.16 0)
				(effects
					(font
						(size 1.27 1.27)
						(thickness 0.15)
					)
					(justify left bottom)
					(hide yes)
				)
			)
			(property "Description" "Interface Bridges, USB to UART, MPSSE, 1.62 V, 1.98 V, VQFN, 56 Pins, -40 °C"
				(at 0 0 0)
				(effects
					(font
						(size 1.27 1.27)
					)
					(hide yes)
				)
			)
			(property "Manufacturer" "FTDI Chip"
				(at 55.88 -12.7 0)
				(effects
					(font
						(size 1.27 1.27)
						(thickness 0.15)
					)
					(justify left bottom)
					(hide yes)
				)
			)
			(property "MPN" "FT4232H-56Q-REEL"
				(at 55.88 -15.24 0)
				(effects
					(font
						(size 1.27 1.27)
						(thickness 0.15)
					)
					(justify left bottom)
					(hide yes)
				)
			)
			(property "Author" "Antmicro"
				(at 55.88 -17.78 0)
				(effects
					(font
						(size 1.27 1.27)
						(thickness 0.15)
					)
					(justify left bottom)
					(hide yes)
				)
			)
			(property "License" "Apache-2.0"
				(at 55.88 -20.32 0)
				(effects
					(font
						(size 1.27 1.27)
						(thickness 0.15)
					)
					(justify left bottom)
					(hide yes)
				)
			)
			(property "ki_keywords" "SMT, INTERFACE, IC, CONTROLLER, USB, UART, I2C, SPI, JTAG"
				(at 0 0 0)
				(effects
					(font
						(size 1.27 1.27)
					)
					(hide yes)
				)
			)
			(symbol "FT4232H_VQFN_1_1"
				(rectangle
					(start 2.54 2.54)
					(end 38.1 -93.98)
					(stroke
						(width 0.254)
						(type default)
					)
					(fill
						(type background)
					)
				)
				(pin power_in line
					(at 0 0 0)
					(length 2.54)
					(name "V_{REGIN}"
						(effects
							(font
								(size 1.27 1.27)
							)
						)
					)
					(number "44"
						(effects
							(font
								(size 1.27 1.27)
							)
						)
					)
				)
				(pin power_in line
					(at 0 -2.54 0)
					(length 2.54)
					(name "V_{CCIO}"
						(effects
							(font
								(size 1.27 1.27)
							)
						)
					)
					(number "16"
						(effects
							(font
								(size 1.27 1.27)
							)
						)
					)
				)
				(pin passive line
					(at 0 -2.54 0)
					(length 2.54)
					(hide yes)
					(name "V_{CCIO}"
						(effects
							(font
								(size 1.27 1.27)
							)
						)
					)
					(number "36"
						(effects
							(font
								(size 1.27 1.27)
							)
						)
					)
				)
				(pin passive line
					(at 0 -2.54 0)
					(length 2.54)
					(hide yes)
					(name "V_{CCIO}"
						(effects
							(font
								(size 1.27 1.27)
							)
						)
					)
					(number "50"
						(effects
							(font
								(size 1.27 1.27)
							)
						)
					)
				)
				(pin power_out line
					(at 0 -6.35 0)
					(length 2.54)
					(name "V_{REGOUT}"
						(effects
							(font
								(size 1.27 1.27)
							)
						)
					)
					(number "43"
						(effects
							(font
								(size 1.27 1.27)
							)
						)
					)
				)
				(pin power_in line
					(at 0 -10.16 0)
					(length 2.54)
					(name "V_{PHY}"
						(effects
							(font
								(size 1.27 1.27)
							)
						)
					)
					(number "5"
						(effects
							(font
								(size 1.27 1.27)
							)
						)
					)
				)
				(pin power_in line
					(at 0 -12.7 0)
					(length 2.54)
					(name "V_{PLL}"
						(effects
							(font
								(size 1.27 1.27)
							)
						)
					)
					(number "9"
						(effects
							(font
								(size 1.27 1.27)
							)
						)
					)
				)
				(pin power_in line
					(at 0 -15.24 0)
					(length 2.54)
					(name "V_{CORE}"
						(effects
							(font
								(size 1.27 1.27)
							)
						)
					)
					(number "2"
						(effects
							(font
								(size 1.27 1.27)
							)
						)
					)
				)
				(pin passive line
					(at 0 -15.24 0)
					(length 2.54)
					(hide yes)
					(name "V_{CORE}"
						(effects
							(font
								(size 1.27 1.27)
							)
						)
					)
					(number "31"
						(effects
							(font
								(size 1.27 1.27)
							)
						)
					)
				)
				(pin bidirectional line
					(at 0 -22.86 0)
					(length 2.54)
					(name "D+"
						(effects
							(font
								(size 1.27 1.27)
							)
						)
					)
					(number "8"
						(effects
							(font
								(size 1.27 1.27)
							)
						)
					)
				)
				(pin bidirectional line
					(at 0 -25.4 0)
					(length 2.54)
					(name "D-"
						(effects
							(font
								(size 1.27 1.27)
							)
						)
					)
					(number "7"
						(effects
							(font
								(size 1.27 1.27)
							)
						)
					)
				)
				(pin input line
					(at 0 -36.83 0)
					(length 2.54)
					(name "~{RESET}"
						(effects
							(font
								(size 1.27 1.27)
							)
						)
					)
					(number "11"
						(effects
							(font
								(size 1.27 1.27)
							)
						)
					)
				)
				(pin bidirectional line
					(at 0 -44.45 0)
					(length 2.54)
					(name "EECS"
						(effects
							(font
								(size 1.27 1.27)
							)
						)
					)
					(number "1"
						(effects
							(font
								(size 1.27 1.27)
							)
						)
					)
				)
				(pin output line
					(at 0 -46.99 0)
					(length 2.54)
					(name "EECLK"
						(effects
							(font
								(size 1.27 1.27)
							)
						)
					)
					(number "56"
						(effects
							(font
								(size 1.27 1.27)
							)
						)
					)
				)
				(pin bidirectional line
					(at 0 -49.53 0)
					(length 2.54)
					(name "EEDATA"
						(effects
							(font
								(size 1.27 1.27)
							)
						)
					)
					(number "55"
						(effects
							(font
								(size 1.27 1.27)
							)
						)
					)
				)
				(pin input line
					(at 0 -54.61 0)
					(length 2.54)
					(name "OSCI"
						(effects
							(font
								(size 1.27 1.27)
							)
						)
					)
					(number "3"
						(effects
							(font
								(size 1.27 1.27)
							)
						)
					)
				)
				(pin output line
					(at 0 -59.69 0)
					(length 2.54)
					(name "OSCO"
						(effects
							(font
								(size 1.27 1.27)
							)
						)
					)
					(number "4"
						(effects
							(font
								(size 1.27 1.27)
							)
						)
					)
				)
				(pin input line
					(at 0 -77.47 0)
					(length 2.54)
					(name "REF"
						(effects
							(font
								(size 1.27 1.27)
							)
						)
					)
					(number "6"
						(effects
							(font
								(size 1.27 1.27)
							)
						)
					)
				)
				(pin input line
					(at 0 -88.9 0)
					(length 2.54)
					(name "TEST"
						(effects
							(font
								(size 1.27 1.27)
							)
						)
					)
					(number "10"
						(effects
							(font
								(size 1.27 1.27)
							)
						)
					)
				)
				(pin power_in line
					(at 0 -91.44 0)
					(length 2.54)
					(name "GND"
						(effects
							(font
								(size 1.27 1.27)
							)
						)
					)
					(number "21"
						(effects
							(font
								(size 1.27 1.27)
							)
						)
					)
				)
				(pin passive line
					(at 0 -91.44 0)
					(length 2.54)
					(hide yes)
					(name "GND"
						(effects
							(font
								(size 1.27 1.27)
							)
						)
					)
					(number "41"
						(effects
							(font
								(size 1.27 1.27)
							)
						)
					)
				)
				(pin passive line
					(at 0 -91.44 0)
					(length 2.54)
					(hide yes)
					(name "GND"
						(effects
							(font
								(size 1.27 1.27)
							)
						)
					)
					(number "45"
						(effects
							(font
								(size 1.27 1.27)
							)
						)
					)
				)
				(pin passive line
					(at 0 -91.44 0)
					(length 2.54)
					(hide yes)
					(name "GND"
						(effects
							(font
								(size 1.27 1.27)
							)
						)
					)
					(number "57"
						(effects
							(font
								(size 1.27 1.27)
							)
						)
					)
				)
				(pin bidirectional line
					(at 40.64 0 180)
					(length 2.54)
					(name "ADBUS0"
						(effects
							(font
								(size 1.27 1.27)
							)
						)
					)
					(number "12"
						(effects
							(font
								(size 1.27 1.27)
							)
						)
					)
				)
				(pin bidirectional line
					(at 40.64 -2.54 180)
					(length 2.54)
					(name "ADBUS1"
						(effects
							(font
								(size 1.27 1.27)
							)
						)
					)
					(number "13"
						(effects
							(font
								(size 1.27 1.27)
							)
						)
					)
				)
				(pin bidirectional line
					(at 40.64 -5.08 180)
					(length 2.54)
					(name "ADBUS2"
						(effects
							(font
								(size 1.27 1.27)
							)
						)
					)
					(number "14"
						(effects
							(font
								(size 1.27 1.27)
							)
						)
					)
				)
				(pin bidirectional line
					(at 40.64 -7.62 180)
					(length 2.54)
					(name "ADBUS3"
						(effects
							(font
								(size 1.27 1.27)
							)
						)
					)
					(number "15"
						(effects
							(font
								(size 1.27 1.27)
							)
						)
					)
				)
				(pin bidirectional line
					(at 40.64 -10.16 180)
					(length 2.54)
					(name "ADBUS4"
						(effects
							(font
								(size 1.27 1.27)
							)
						)
					)
					(number "17"
						(effects
							(font
								(size 1.27 1.27)
							)
						)
					)
				)
				(pin bidirectional line
					(at 40.64 -12.7 180)
					(length 2.54)
					(name "ADBUS5"
						(effects
							(font
								(size 1.27 1.27)
							)
						)
					)
					(number "18"
						(effects
							(font
								(size 1.27 1.27)
							)
						)
					)
				)
				(pin bidirectional line
					(at 40.64 -15.24 180)
					(length 2.54)
					(name "ADBUS6"
						(effects
							(font
								(size 1.27 1.27)
							)
						)
					)
					(number "19"
						(effects
							(font
								(size 1.27 1.27)
							)
						)
					)
				)
				(pin bidirectional line
					(at 40.64 -17.78 180)
					(length 2.54)
					(name "ADBUS7"
						(effects
							(font
								(size 1.27 1.27)
							)
						)
					)
					(number "20"
						(effects
							(font
								(size 1.27 1.27)
							)
						)
					)
				)
				(pin bidirectional line
					(at 40.64 -21.59 180)
					(length 2.54)
					(name "BDBUS0"
						(effects
							(font
								(size 1.27 1.27)
							)
						)
					)
					(number "22"
						(effects
							(font
								(size 1.27 1.27)
							)
						)
					)
				)
				(pin bidirectional line
					(at 40.64 -24.13 180)
					(length 2.54)
					(name "BDBUS1"
						(effects
							(font
								(size 1.27 1.27)
							)
						)
					)
					(number "23"
						(effects
							(font
								(size 1.27 1.27)
							)
						)
					)
				)
				(pin bidirectional line
					(at 40.64 -26.67 180)
					(length 2.54)
					(name "BDBUS2"
						(effects
							(font
								(size 1.27 1.27)
							)
						)
					)
					(number "24"
						(effects
							(font
								(size 1.27 1.27)
							)
						)
					)
				)
				(pin bidirectional line
					(at 40.64 -29.21 180)
					(length 2.54)
					(name "BDBUS3"
						(effects
							(font
								(size 1.27 1.27)
							)
						)
					)
					(number "25"
						(effects
							(font
								(size 1.27 1.27)
							)
						)
					)
				)
				(pin bidirectional line
					(at 40.64 -31.75 180)
					(length 2.54)
					(name "BDBUS4"
						(effects
							(font
								(size 1.27 1.27)
							)
						)
					)
					(number "26"
						(effects
							(font
								(size 1.27 1.27)
							)
						)
					)
				)
				(pin bidirectional line
					(at 40.64 -34.29 180)
					(length 2.54)
					(name "BDBUS5"
						(effects
							(font
								(size 1.27 1.27)
							)
						)
					)
					(number "27"
						(effects
							(font
								(size 1.27 1.27)
							)
						)
					)
				)
				(pin bidirectional line
					(at 40.64 -36.83 180)
					(length 2.54)
					(name "BDBUS6"
						(effects
							(font
								(size 1.27 1.27)
							)
						)
					)
					(number "28"
						(effects
							(font
								(size 1.27 1.27)
							)
						)
					)
				)
				(pin bidirectional line
					(at 40.64 -39.37 180)
					(length 2.54)
					(name "BDBUS7"
						(effects
							(font
								(size 1.27 1.27)
							)
						)
					)
					(number "29"
						(effects
							(font
								(size 1.27 1.27)
							)
						)
					)
				)
				(pin bidirectional line
					(at 40.64 -43.18 180)
					(length 2.54)
					(name "CDBUS0"
						(effects
							(font
								(size 1.27 1.27)
							)
						)
					)
					(number "32"
						(effects
							(font
								(size 1.27 1.27)
							)
						)
					)
				)
				(pin bidirectional line
					(at 40.64 -45.72 180)
					(length 2.54)
					(name "CDBUS1"
						(effects
							(font
								(size 1.27 1.27)
							)
						)
					)
					(number "33"
						(effects
							(font
								(size 1.27 1.27)
							)
						)
					)
				)
				(pin bidirectional line
					(at 40.64 -48.26 180)
					(length 2.54)
					(name "CDBUS2"
						(effects
							(font
								(size 1.27 1.27)
							)
						)
					)
					(number "34"
						(effects
							(font
								(size 1.27 1.27)
							)
						)
					)
				)
				(pin bidirectional line
					(at 40.64 -50.8 180)
					(length 2.54)
					(name "CDBUS3"
						(effects
							(font
								(size 1.27 1.27)
							)
						)
					)
					(number "35"
						(effects
							(font
								(size 1.27 1.27)
							)
						)
					)
				)
				(pin bidirectional line
					(at 40.64 -53.34 180)
					(length 2.54)
					(name "CDBUS4"
						(effects
							(font
								(size 1.27 1.27)
							)
						)
					)
					(number "37"
						(effects
							(font
								(size 1.27 1.27)
							)
						)
					)
				)
				(pin bidirectional line
					(at 40.64 -55.88 180)
					(length 2.54)
					(name "CDBUS5"
						(effects
							(font
								(size 1.27 1.27)
							)
						)
					)
					(number "38"
						(effects
							(font
								(size 1.27 1.27)
							)
						)
					)
				)
				(pin bidirectional line
					(at 40.64 -58.42 180)
					(length 2.54)
					(name "CDBUS6"
						(effects
							(font
								(size 1.27 1.27)
							)
						)
					)
					(number "39"
						(effects
							(font
								(size 1.27 1.27)
							)
						)
					)
				)
				(pin bidirectional line
					(at 40.64 -60.96 180)
					(length 2.54)
					(name "CDBUS7"
						(effects
							(font
								(size 1.27 1.27)
							)
						)
					)
					(number "40"
						(effects
							(font
								(size 1.27 1.27)
							)
						)
					)
				)
				(pin bidirectional line
					(at 40.64 -64.77 180)
					(length 2.54)
					(name "DDBUS0"
						(effects
							(font
								(size 1.27 1.27)
							)
						)
					)
					(number "42"
						(effects
							(font
								(size 1.27 1.27)
							)
						)
					)
				)
				(pin bidirectional line
					(at 40.64 -67.31 180)
					(length 2.54)
					(name "DDBUS1"
						(effects
							(font
								(size 1.27 1.27)
							)
						)
					)
					(number "46"
						(effects
							(font
								(size 1.27 1.27)
							)
						)
					)
				)
				(pin bidirectional line
					(at 40.64 -69.85 180)
					(length 2.54)
					(name "DDBUS2"
						(effects
							(font
								(size 1.27 1.27)
							)
						)
					)
					(number "47"
						(effects
							(font
								(size 1.27 1.27)
							)
						)
					)
				)
				(pin bidirectional line
					(at 40.64 -72.39 180)
					(length 2.54)
					(name "DDBUS3"
						(effects
							(font
								(size 1.27 1.27)
							)
						)
					)
					(number "48"
						(effects
							(font
								(size 1.27 1.27)
							)
						)
					)
				)
				(pin bidirectional line
					(at 40.64 -74.93 180)
					(length 2.54)
					(name "DDBUS4"
						(effects
							(font
								(size 1.27 1.27)
							)
						)
					)
					(number "49"
						(effects
							(font
								(size 1.27 1.27)
							)
						)
					)
				)
				(pin bidirectional line
					(at 40.64 -77.47 180)
					(length 2.54)
					(name "DDBUS5"
						(effects
							(font
								(size 1.27 1.27)
							)
						)
					)
					(number "51"
						(effects
							(font
								(size 1.27 1.27)
							)
						)
					)
				)
				(pin bidirectional line
					(at 40.64 -80.01 180)
					(length 2.54)
					(name "DDBUS6"
						(effects
							(font
								(size 1.27 1.27)
							)
						)
					)
					(number "52"
						(effects
							(font
								(size 1.27 1.27)
							)
						)
					)
				)
				(pin bidirectional line
					(at 40.64 -82.55 180)
					(length 2.54)
					(name "DDBUS7"
						(effects
							(font
								(size 1.27 1.27)
							)
						)
					)
					(number "53"
						(effects
							(font
								(size 1.27 1.27)
							)
						)
					)
				)
				(pin output line
					(at 40.64 -87.63 180)
					(length 2.54)
					(name "~{PWR_{EN}}"
						(effects
							(font
								(size 1.27 1.27)
							)
						)
					)
					(number "54"
						(effects
							(font
								(size 1.27 1.27)
							)
						)
					)
				)
				(pin output line
					(at 40.64 -90.17 180)
					(length 2.54)
					(name "~{SUSPEND}"
						(effects
							(font
								(size 1.27 1.27)
							)
						)
					)
					(number "30"
						(effects
							(font
								(size 1.27 1.27)
							)
						)
					)
				)
			)
		)
	(symbol "antmicroInterfaceControllers:KSZ9031RNXCA"
			(exclude_from_sim no)
			(in_bom yes)
			(on_board yes)
			(property "Reference" "U"
				(at 76.2 -5.08 0)
				(effects
					(font
						(size 1.27 1.27)
						(thickness 0.15)
					)
					(justify left bottom)
				)
			)
			(property "Value" "KSZ9031RNXCA"
				(at 76.2 -7.62 0)
				(effects
					(font
						(size 1.27 1.27)
						(thickness 0.15)
					)
					(justify left bottom)
				)
			)
			(property "Footprint" "antmicro-footprints:QFN-48-1EP_7x7x0.9mm_P0.5mm_EP3.5x3.5mm"
				(at 76.2 -10.16 0)
				(effects
					(font
						(size 1.27 1.27)
						(thickness 0.15)
					)
					(justify left bottom)
					(hide yes)
				)
			)
			(property "Datasheet" "http://ww1.microchip.com/downloads/en/DeviceDoc/00002117F.pdf"
				(at 76.2 -12.7 0)
				(effects
					(font
						(size 1.27 1.27)
						(thickness 0.15)
					)
					(justify left bottom)
					(hide yes)
				)
			)
			(property "Description" "Ethernet Controller, 1000 Mbps, IEEE 802.3, 1.14 V, 3.465 V, QFN, 48 Pins"
				(at 0 0 0)
				(effects
					(font
						(size 1.27 1.27)
					)
					(hide yes)
				)
			)
			(property "Manufacturer" "Microchip Technology"
				(at 76.2 -15.24 0)
				(effects
					(font
						(size 1.27 1.27)
						(thickness 0.15)
					)
					(justify left bottom)
					(hide yes)
				)
			)
			(property "MPN" "KSZ9031RNXCA"
				(at 76.2 -17.78 0)
				(effects
					(font
						(size 1.27 1.27)
						(thickness 0.15)
					)
					(justify left bottom)
					(hide yes)
				)
			)
			(property "Author" "Antmicro"
				(at 76.2 -20.32 0)
				(effects
					(font
						(size 1.27 1.27)
						(thickness 0.15)
					)
					(justify left bottom)
					(hide yes)
				)
			)
			(property "License" "Apache-2.0"
				(at 76.2 -22.86 0)
				(effects
					(font
						(size 1.27 1.27)
						(thickness 0.15)
					)
					(justify left bottom)
					(hide yes)
				)
			)
			(property "ki_keywords" "SMT, TRANSCEIVER, IC, ETHERNET, PHY"
				(at 0 0 0)
				(effects
					(font
						(size 1.27 1.27)
					)
					(hide yes)
				)
			)
			(symbol "KSZ9031RNXCA_1_1"
				(rectangle
					(start 2.54 2.54)
					(end 41.91 -62.23)
					(stroke
						(width 0.254)
						(type default)
					)
					(fill
						(type background)
					)
				)
				(text "10/100/1000"
					(at 21.59 -1.27 0)
					(effects
						(font
							(size 1.27 1.27)
							(thickness 0.15)
						)
						(justify bottom)
					)
				)
				(text "Ethernet PHY"
					(at 21.59 -3.81 0)
					(effects
						(font
							(size 1.27 1.27)
							(thickness 0.15)
						)
						(justify bottom)
					)
				)
				(pin power_in line
					(at 0 0 0)
					(length 2.54)
					(name "DVDDH"
						(effects
							(font
								(size 1.27 1.27)
							)
						)
					)
					(number "16"
						(effects
							(font
								(size 1.27 1.27)
							)
						)
					)
				)
				(pin passive line
					(at 0 0 0)
					(length 2.54)
					(hide yes)
					(name "DVDDH"
						(effects
							(font
								(size 1.27 1.27)
							)
						)
					)
					(number "34"
						(effects
							(font
								(size 1.27 1.27)
							)
						)
					)
				)
				(pin passive line
					(at 0 0 0)
					(length 2.54)
					(hide yes)
					(name "DVDDH"
						(effects
							(font
								(size 1.27 1.27)
							)
						)
					)
					(number "40"
						(effects
							(font
								(size 1.27 1.27)
							)
						)
					)
				)
				(pin power_in line
					(at 0 -3.81 0)
					(length 2.54)
					(name "AVDDH"
						(effects
							(font
								(size 1.27 1.27)
							)
						)
					)
					(number "1"
						(effects
							(font
								(size 1.27 1.27)
							)
						)
					)
				)
				(pin passive line
					(at 0 -3.81 0)
					(length 2.54)
					(hide yes)
					(name "AVDDH"
						(effects
							(font
								(size 1.27 1.27)
							)
						)
					)
					(number "12"
						(effects
							(font
								(size 1.27 1.27)
							)
						)
					)
				)
				(pin input line
					(at 0 -7.62 0)
					(length 2.54)
					(name "~{RESET}"
						(effects
							(font
								(size 1.27 1.27)
							)
						)
					)
					(number "42"
						(effects
							(font
								(size 1.27 1.27)
							)
						)
					)
				)
				(pin input line
					(at 0 -10.16 0)
					(length 2.54)
					(name "~{INT/PME}"
						(effects
							(font
								(size 1.27 1.27)
							)
						)
					)
					(number "38"
						(effects
							(font
								(size 1.27 1.27)
							)
						)
					)
				)
				(pin input line
					(at 0 -13.97 0)
					(length 2.54)
					(name "MDC"
						(effects
							(font
								(size 1.27 1.27)
							)
						)
					)
					(number "36"
						(effects
							(font
								(size 1.27 1.27)
							)
						)
					)
				)
				(pin input line
					(at 0 -16.51 0)
					(length 2.54)
					(name "MDIO"
						(effects
							(font
								(size 1.27 1.27)
							)
						)
					)
					(number "37"
						(effects
							(font
								(size 1.27 1.27)
							)
						)
					)
				)
				(pin input line
					(at 0 -20.32 0)
					(length 2.54)
					(name "TX_EN"
						(effects
							(font
								(size 1.27 1.27)
							)
						)
					)
					(number "25"
						(effects
							(font
								(size 1.27 1.27)
							)
						)
					)
				)
				(pin input line
					(at 0 -22.86 0)
					(length 2.54)
					(name "TXD0"
						(effects
							(font
								(size 1.27 1.27)
							)
						)
					)
					(number "19"
						(effects
							(font
								(size 1.27 1.27)
							)
						)
					)
				)
				(pin input line
					(at 0 -25.4 0)
					(length 2.54)
					(name "TXD1"
						(effects
							(font
								(size 1.27 1.27)
							)
						)
					)
					(number "20"
						(effects
							(font
								(size 1.27 1.27)
							)
						)
					)
				)
				(pin input line
					(at 0 -27.94 0)
					(length 2.54)
					(name "TXD2"
						(effects
							(font
								(size 1.27 1.27)
							)
						)
					)
					(number "21"
						(effects
							(font
								(size 1.27 1.27)
							)
						)
					)
				)
				(pin input line
					(at 0 -30.48 0)
					(length 2.54)
					(name "TXD3"
						(effects
							(font
								(size 1.27 1.27)
							)
						)
					)
					(number "22"
						(effects
							(font
								(size 1.27 1.27)
							)
						)
					)
				)
				(pin input clock
					(at 0 -33.02 0)
					(length 2.54)
					(name "GTX_CLK"
						(effects
							(font
								(size 1.27 1.27)
							)
						)
					)
					(number "24"
						(effects
							(font
								(size 1.27 1.27)
							)
						)
					)
				)
				(pin input line
					(at 0 -36.83 0)
					(length 2.54)
					(name "RX_DV/CLK125_EN"
						(effects
							(font
								(size 1.27 1.27)
							)
						)
					)
					(number "33"
						(effects
							(font
								(size 1.27 1.27)
							)
						)
					)
				)
				(pin input line
					(at 0 -39.37 0)
					(length 2.54)
					(name "RXD0/MODE0"
						(effects
							(font
								(size 1.27 1.27)
							)
						)
					)
					(number "32"
						(effects
							(font
								(size 1.27 1.27)
							)
						)
					)
				)
				(pin input line
					(at 0 -41.91 0)
					(length 2.54)
					(name "RXD1/MODE1"
						(effects
							(font
								(size 1.27 1.27)
							)
						)
					)
					(number "31"
						(effects
							(font
								(size 1.27 1.27)
							)
						)
					)
				)
				(pin input line
					(at 0 -44.45 0)
					(length 2.54)
					(name "RXD2/MODE2"
						(effects
							(font
								(size 1.27 1.27)
							)
						)
					)
					(number "28"
						(effects
							(font
								(size 1.27 1.27)
							)
						)
					)
				)
				(pin input line
					(at 0 -46.99 0)
					(length 2.54)
					(name "RXD3/MODE3"
						(effects
							(font
								(size 1.27 1.27)
							)
						)
					)
					(number "27"
						(effects
							(font
								(size 1.27 1.27)
							)
						)
					)
				)
				(pin input clock
					(at 0 -49.53 0)
					(length 2.54)
					(name "RX_CLK/PHYAD2"
						(effects
							(font
								(size 1.27 1.27)
							)
						)
					)
					(number "35"
						(effects
							(font
								(size 1.27 1.27)
							)
						)
					)
				)
				(pin input clock
					(at 0 -53.34 0)
					(length 2.54)
					(name "CLK125_NDO/LED_MODE"
						(effects
							(font
								(size 1.27 1.27)
							)
						)
					)
					(number "41"
						(effects
							(font
								(size 1.27 1.27)
							)
						)
					)
				)
				(pin input line
					(at 0 -57.15 0)
					(length 2.54)
					(name "XI"
						(effects
							(font
								(size 1.27 1.27)
							)
						)
					)
					(number "46"
						(effects
							(font
								(size 1.27 1.27)
							)
						)
					)
				)
				(pin input line
					(at 0 -59.69 0)
					(length 2.54)
					(name "XO"
						(effects
							(font
								(size 1.27 1.27)
							)
						)
					)
					(number "45"
						(effects
							(font
								(size 1.27 1.27)
							)
						)
					)
				)
				(pin no_connect line
					(at 25.4 -62.23 90)
					(length 2.54)
					(hide yes)
					(name "NC"
						(effects
							(font
								(size 1.27 1.27)
							)
						)
					)
					(number "13"
						(effects
							(font
								(size 1.27 1.27)
							)
						)
					)
				)
				(pin no_connect line
					(at 28.575 -62.23 90)
					(length 2.54)
					(hide yes)
					(name "NC"
						(effects
							(font
								(size 1.27 1.27)
							)
						)
					)
					(number "47"
						(effects
							(font
								(size 1.27 1.27)
							)
						)
					)
				)
				(pin power_in line
					(at 44.45 0 180)
					(length 2.54)
					(name "DVDDL"
						(effects
							(font
								(size 1.27 1.27)
							)
						)
					)
					(number "14"
						(effects
							(font
								(size 1.27 1.27)
							)
						)
					)
				)
				(pin passive line
					(at 44.45 0 180)
					(length 2.54)
					(hide yes)
					(name "DVDDL"
						(effects
							(font
								(size 1.27 1.27)
							)
						)
					)
					(number "18"
						(effects
							(font
								(size 1.27 1.27)
							)
						)
					)
				)
				(pin passive line
					(at 44.45 0 180)
					(length 2.54)
					(hide yes)
					(name "DVDDL"
						(effects
							(font
								(size 1.27 1.27)
							)
						)
					)
					(number "23"
						(effects
							(font
								(size 1.27 1.27)
							)
						)
					)
				)
				(pin passive line
					(at 44.45 0 180)
					(length 2.54)
					(hide yes)
					(name "DVDDL"
						(effects
							(font
								(size 1.27 1.27)
							)
						)
					)
					(number "26"
						(effects
							(font
								(size 1.27 1.27)
							)
						)
					)
				)
				(pin passive line
					(at 44.45 0 180)
					(length 2.54)
					(hide yes)
					(name "DVDDL"
						(effects
							(font
								(size 1.27 1.27)
							)
						)
					)
					(number "30"
						(effects
							(font
								(size 1.27 1.27)
							)
						)
					)
				)
				(pin passive line
					(at 44.45 0 180)
					(length 2.54)
					(hide yes)
					(name "DVDDL"
						(effects
							(font
								(size 1.27 1.27)
							)
						)
					)
					(number "39"
						(effects
							(font
								(size 1.27 1.27)
							)
						)
					)
				)
				(pin power_in line
					(at 44.45 -3.81 180)
					(length 2.54)
					(name "AVDDL"
						(effects
							(font
								(size 1.27 1.27)
							)
						)
					)
					(number "4"
						(effects
							(font
								(size 1.27 1.27)
							)
						)
					)
				)
				(pin passive line
					(at 44.45 -3.81 180)
					(length 2.54)
					(hide yes)
					(name "AVDDL"
						(effects
							(font
								(size 1.27 1.27)
							)
						)
					)
					(number "9"
						(effects
							(font
								(size 1.27 1.27)
							)
						)
					)
				)
				(pin power_in line
					(at 44.45 -6.35 180)
					(length 2.54)
					(name "AVDDL_PLL"
						(effects
							(font
								(size 1.27 1.27)
							)
						)
					)
					(number "44"
						(effects
							(font
								(size 1.27 1.27)
							)
						)
					)
				)
				(pin input line
					(at 44.45 -8.89 180)
					(length 2.54)
					(name "LDO_O"
						(effects
							(font
								(size 1.27 1.27)
							)
						)
					)
					(number "43"
						(effects
							(font
								(size 1.27 1.27)
							)
						)
					)
				)
				(pin bidirectional line
					(at 44.45 -13.97 180)
					(length 2.54)
					(name "TXRXP_A"
						(effects
							(font
								(size 1.27 1.27)
							)
						)
					)
					(number "2"
						(effects
							(font
								(size 1.27 1.27)
							)
						)
					)
				)
				(pin bidirectional line
					(at 44.45 -16.51 180)
					(length 2.54)
					(name "TXRXM_A"
						(effects
							(font
								(size 1.27 1.27)
							)
						)
					)
					(number "3"
						(effects
							(font
								(size 1.27 1.27)
							)
						)
					)
				)
				(pin bidirectional line
					(at 44.45 -20.32 180)
					(length 2.54)
					(name "TXRXP_B"
						(effects
							(font
								(size 1.27 1.27)
							)
						)
					)
					(number "5"
						(effects
							(font
								(size 1.27 1.27)
							)
						)
					)
				)
				(pin bidirectional line
					(at 44.45 -22.86 180)
					(length 2.54)
					(name "TXRXM_B"
						(effects
							(font
								(size 1.27 1.27)
							)
						)
					)
					(number "6"
						(effects
							(font
								(size 1.27 1.27)
							)
						)
					)
				)
				(pin bidirectional line
					(at 44.45 -26.67 180)
					(length 2.54)
					(name "TXRXP_C"
						(effects
							(font
								(size 1.27 1.27)
							)
						)
					)
					(number "7"
						(effects
							(font
								(size 1.27 1.27)
							)
						)
					)
				)
				(pin bidirectional line
					(at 44.45 -29.21 180)
					(length 2.54)
					(name "TXRXM_C"
						(effects
							(font
								(size 1.27 1.27)
							)
						)
					)
					(number "8"
						(effects
							(font
								(size 1.27 1.27)
							)
						)
					)
				)
				(pin bidirectional line
					(at 44.45 -33.02 180)
					(length 2.54)
					(name "TXRXP_D"
						(effects
							(font
								(size 1.27 1.27)
							)
						)
					)
					(number "10"
						(effects
							(font
								(size 1.27 1.27)
							)
						)
					)
				)
				(pin bidirectional line
					(at 44.45 -35.56 180)
					(length 2.54)
					(name "TXRXM_D"
						(effects
							(font
								(size 1.27 1.27)
							)
						)
					)
					(number "11"
						(effects
							(font
								(size 1.27 1.27)
							)
						)
					)
				)
				(pin bidirectional line
					(at 44.45 -41.91 180)
					(length 2.54)
					(name "LED1/PHAD0/PME_N1"
						(effects
							(font
								(size 1.27 1.27)
							)
						)
					)
					(number "17"
						(effects
							(font
								(size 1.27 1.27)
							)
						)
					)
				)
				(pin bidirectional line
					(at 44.45 -44.45 180)
					(length 2.54)
					(name "LED2/PHYAD1"
						(effects
							(font
								(size 1.27 1.27)
							)
						)
					)
					(number "15"
						(effects
							(font
								(size 1.27 1.27)
							)
						)
					)
				)
				(pin output line
					(at 44.45 -49.53 180)
					(length 2.54)
					(name "ISET"
						(effects
							(font
								(size 1.27 1.27)
							)
						)
					)
					(number "48"
						(effects
							(font
								(size 1.27 1.27)
							)
						)
					)
				)
				(pin power_in line
					(at 44.45 -57.15 180)
					(length 2.54)
					(name "PAD_GND"
						(effects
							(font
								(size 1.27 1.27)
							)
						)
					)
					(number "49"
						(effects
							(font
								(size 1.27 1.27)
							)
						)
					)
				)
				(pin power_in line
					(at 44.45 -59.69 180)
					(length 2.54)
					(name "VSS"
						(effects
							(font
								(size 1.27 1.27)
							)
						)
					)
					(number "29"
						(effects
							(font
								(size 1.27 1.27)
							)
						)
					)
				)
			)
		)
	(symbol "antmicroLEDIndicationDiscrete:LED_G_0603_KP-1608CGCK"
			(pin_names
				(hide yes)
			)
			(exclude_from_sim no)
			(in_bom yes)
			(on_board yes)
			(property "Reference" "D"
				(at 22.86 -5.08 0)
				(effects
					(font
						(size 1.27 1.27)
						(thickness 0.15)
					)
					(justify left bottom)
				)
			)
			(property "Value" "LED_G_0603_KP-1608CGCK"
				(at 22.86 -7.62 0)
				(effects
					(font
						(size 1.27 1.27)
						(thickness 0.15)
					)
					(justify left bottom)
				)
			)
			(property "Footprint" "antmicro-footprints:LED_0603_1608Metric_G"
				(at 22.86 -10.16 0)
				(effects
					(font
						(size 1.27 1.27)
						(thickness 0.15)
					)
					(justify left bottom)
					(hide yes)
				)
			)
			(property "Datasheet" "http://www.farnell.com/datasheets/2045956.pdf"
				(at 22.86 -12.7 0)
				(effects
					(font
						(size 1.27 1.27)
						(thickness 0.15)
					)
					(justify left bottom)
					(hide yes)
				)
			)
			(property "Description" ""
				(at 0 0 0)
				(effects
					(font
						(size 1.27 1.27)
					)
					(hide yes)
				)
			)
			(property "MPN" "KP-1608CGCK"
				(at 22.86 -15.24 0)
				(effects
					(font
						(size 1.27 1.27)
						(thickness 0.15)
					)
					(justify left bottom)
					(hide yes)
				)
			)
			(property "Manufacturer" "Kingbright"
				(at 22.86 -17.78 0)
				(effects
					(font
						(size 1.27 1.27)
						(thickness 0.15)
					)
					(justify left bottom)
					(hide yes)
				)
			)
			(property "Author" "Antmicro"
				(at 22.86 -20.32 0)
				(effects
					(font
						(size 1.27 1.27)
						(thickness 0.15)
					)
					(justify left bottom)
					(hide yes)
				)
			)
			(property "License" "Apache-2.0"
				(at 22.86 -22.86 0)
				(effects
					(font
						(size 1.27 1.27)
						(thickness 0.15)
					)
					(justify left bottom)
					(hide yes)
				)
			)
			(symbol "LED_G_0603_KP-1608CGCK_1_1"
				(polyline
					(pts
						(xy 2.54 1.27) (xy 2.54 -1.27) (xy 5.08 0) (xy 2.54 1.27)
					)
					(stroke
						(width 0.254)
						(type default)
					)
					(fill
						(type outline)
					)
				)
				(polyline
					(pts
						(xy 3.683 2.286) (xy 3.683 1.778) (xy 3.683 2.286) (xy 3.175 2.286) (xy 3.683 2.286) (xy 2.794 1.397)
					)
					(stroke
						(width 0.254)
						(type default)
					)
					(fill
						(type none)
					)
				)
				(polyline
					(pts
						(xy 4.699 2.032) (xy 4.699 1.524) (xy 4.699 2.032) (xy 4.191 2.032) (xy 4.699 2.032) (xy 3.683 1.016)
					)
					(stroke
						(width 0.254)
						(type default)
					)
					(fill
						(type none)
					)
				)
				(polyline
					(pts
						(xy 5.08 1.27) (xy 5.08 -1.27)
					)
					(stroke
						(width 0.254)
						(type default)
					)
					(fill
						(type none)
					)
				)
				(pin passive line
					(at 0 0 0)
					(length 2.54)
					(name "1"
						(effects
							(font
								(size 1.27 1.27)
							)
						)
					)
					(number "1"
						(effects
							(font
								(size 1.27 1.27)
							)
						)
					)
				)
				(pin passive line
					(at 7.62 0 180)
					(length 2.54)
					(name "2"
						(effects
							(font
								(size 1.27 1.27)
							)
						)
					)
					(number "2"
						(effects
							(font
								(size 1.27 1.27)
							)
						)
					)
				)
			)
		)
	(symbol "antmicroMechanicalParts:Spacer_Drill3.7mm_H5mm_9774050151R"
			(exclude_from_sim no)
			(in_bom yes)
			(on_board yes)
			(property "Reference" "H"
				(at 22.86 -2.54 0)
				(effects
					(font
						(size 1.27 1.27)
						(thickness 0.15)
					)
					(justify left bottom)
				)
			)
			(property "Value" "Spacer_Drill3.7mm_H5mm_9774050151R"
				(at 22.86 -5.08 0)
				(effects
					(font
						(size 1.27 1.27)
						(thickness 0.15)
					)
					(justify left bottom)
				)
			)
			(property "Footprint" "antmicro-footprints:Spacer_Drill3.7mm_H5mm_9774050151R"
				(at 22.86 -7.62 0)
				(effects
					(font
						(size 1.27 1.27)
						(thickness 0.15)
					)
					(justify left bottom)
					(hide yes)
				)
			)
			(property "Datasheet" "https://www.we-online.com/catalog/datasheet/9774050151.pdf"
				(at 22.86 -10.16 0)
				(effects
					(font
						(size 1.27 1.27)
						(thickness 0.15)
					)
					(justify left bottom)
					(hide yes)
				)
			)
			(property "Description" "Spacer, SMT, Non Stop, Steel, Swage Round, 5.1 mm x 5 mm, M2.5 Thread, WA-SMSI Series"
				(at 0 0 0)
				(effects
					(font
						(size 1.27 1.27)
					)
					(hide yes)
				)
			)
			(property "Manufacturer" "Würth Elektronik"
				(at 22.86 -12.7 0)
				(effects
					(font
						(size 1.27 1.27)
						(thickness 0.15)
					)
					(justify left bottom)
					(hide yes)
				)
			)
			(property "MPN" "9774050151R"
				(at 22.86 -15.24 0)
				(effects
					(font
						(size 1.27 1.27)
						(thickness 0.15)
					)
					(justify left bottom)
					(hide yes)
				)
			)
			(property "Author" "Antmicro"
				(at 22.86 -17.78 0)
				(effects
					(font
						(size 1.27 1.27)
						(thickness 0.15)
					)
					(justify left bottom)
					(hide yes)
				)
			)
			(property "License" "Apache-2.0"
				(at 22.86 -20.32 0)
				(effects
					(font
						(size 1.27 1.27)
						(thickness 0.15)
					)
					(justify left bottom)
					(hide yes)
				)
			)
			(property "ki_keywords" "SPACER"
				(at 0 0 0)
				(effects
					(font
						(size 1.27 1.27)
					)
					(hide yes)
				)
			)
			(symbol "Spacer_Drill3.7mm_H5mm_9774050151R_1_1"
				(rectangle
					(start 2.54 -2.54)
					(end 7.62 2.54)
					(stroke
						(width 0.254)
						(type default)
					)
					(fill
						(type background)
					)
				)
				(rectangle
					(start 3.81 -1.27)
					(end 6.35 1.27)
					(stroke
						(width 0.254)
						(type default)
					)
					(fill
						(type background)
					)
				)
				(pin passive line
					(at 0 0 0)
					(length 2.54)
					(name "~"
						(effects
							(font
								(size 1.27 1.27)
							)
						)
					)
					(number "1"
						(effects
							(font
								(size 1.27 1.27)
							)
						)
					)
				)
			)
		)
	(symbol "antmicroMechanicalParts:antmicro_logo"
			(exclude_from_sim no)
			(in_bom yes)
			(on_board yes)
			(property "Reference" "N1"
				(at 5.08 1.27 0)
				(effects
					(font
						(size 1.27 1.27)
					)
					(justify left bottom)
				)
			)
			(property "Value" "antmicro_logo"
				(at 5.08 -0.635 0)
				(effects
					(font
						(size 1.27 1.27)
						(thickness 0.15)
					)
					(justify left bottom)
				)
			)
			(property "Footprint" "antmicro-footprints:antmicro-logo"
				(at 15.24 -10.16 0)
				(effects
					(font
						(size 1.27 1.27)
						(thickness 0.15)
					)
					(justify left bottom)
					(hide yes)
				)
			)
			(property "Datasheet" ""
				(at 15.24 -12.7 0)
				(effects
					(font
						(size 1.27 1.27)
						(thickness 0.15)
					)
					(justify left bottom)
					(hide yes)
				)
			)
			(property "Description" ""
				(at 0 0 0)
				(effects
					(font
						(size 1.27 1.27)
					)
					(hide yes)
				)
			)
			(property "MPN" ""
				(at 0 0 0)
				(effects
					(font
						(size 1.27 1.27)
					)
					(hide yes)
				)
			)
			(property "Manufacturer" ""
				(at 15.24 -20.32 0)
				(effects
					(font
						(size 1.27 1.27)
						(thickness 0.15)
					)
					(justify left bottom)
					(hide yes)
				)
			)
			(property "Author" "Antmicro"
				(at 15.24 -15.24 0)
				(effects
					(font
						(size 1.27 1.27)
						(thickness 0.15)
					)
					(justify left bottom)
					(hide yes)
				)
			)
			(property "License" "Apache-2.0"
				(at 15.24 -17.78 0)
				(effects
					(font
						(size 1.27 1.27)
						(thickness 0.15)
					)
					(justify left bottom)
					(hide yes)
				)
			)
			(symbol "antmicro_logo_1_1"
				(text "Logo"
					(at 0 0 0)
					(effects
						(font
							(size 1.27 1.27)
							(thickness 0.15)
						)
						(justify left bottom)
					)
				)
			)
		)
	(symbol "antmicroMechanicalParts:oshw_logo"
			(exclude_from_sim no)
			(in_bom yes)
			(on_board yes)
			(property "Reference" "N"
				(at 15.24 -5.08 0)
				(effects
					(font
						(size 1.27 1.27)
						(thickness 0.15)
					)
					(justify left bottom)
				)
			)
			(property "Value" "oshw_logo"
				(at 15.24 -7.62 0)
				(effects
					(font
						(size 1.27 1.27)
						(thickness 0.15)
					)
					(justify left bottom)
				)
			)
			(property "Footprint" "antmicro-footprints:oshw-logo"
				(at 15.24 -10.16 0)
				(effects
					(font
						(size 1.27 1.27)
						(thickness 0.15)
					)
					(justify left bottom)
					(hide yes)
				)
			)
			(property "Datasheet" ""
				(at 15.24 -12.7 0)
				(effects
					(font
						(size 1.27 1.27)
						(thickness 0.15)
					)
					(justify left bottom)
					(hide yes)
				)
			)
			(property "Description" ""
				(at 0 0 0)
				(effects
					(font
						(size 1.27 1.27)
					)
					(hide yes)
				)
			)
			(property "Author" "Antmicro"
				(at 15.24 -15.24 0)
				(effects
					(font
						(size 1.27 1.27)
						(thickness 0.15)
					)
					(justify left bottom)
					(hide yes)
				)
			)
			(property "License" "Apache-2.0"
				(at 15.24 -17.78 0)
				(effects
					(font
						(size 1.27 1.27)
						(thickness 0.15)
					)
					(justify left bottom)
					(hide yes)
				)
			)
			(property "MPN" ""
				(at 0 0 0)
				(effects
					(font
						(size 1.27 1.27)
					)
					(hide yes)
				)
			)
			(property "Manufacturer" ""
				(at 15.24 -20.32 0)
				(effects
					(font
						(size 1.27 1.27)
						(thickness 0.15)
					)
					(justify left bottom)
					(hide yes)
				)
			)
			(symbol "oshw_logo_1_1"
				(text "Logo"
					(at 0 0 0)
					(effects
						(font
							(size 1.27 1.27)
							(thickness 0.15)
						)
						(justify left bottom)
					)
				)
			)
		)
	(symbol "antmicroMemory:S25FL128LAGNFA010"
			(exclude_from_sim no)
			(in_bom yes)
			(on_board yes)
			(property "Reference" "U"
				(at 40.64 -2.54 0)
				(effects
					(font
						(size 1.27 1.27)
						(thickness 0.15)
					)
					(justify left bottom)
				)
			)
			(property "Value" "S25FL128LAGNFA010"
				(at 40.64 -7.62 0)
				(effects
					(font
						(size 1.27 1.27)
						(thickness 0.15)
					)
					(justify left bottom)
					(hide yes)
				)
			)
			(property "Footprint" "antmicro-footprints:WSON-8_6x8x0.5mm_P1.27mm"
				(at 40.64 -10.16 0)
				(effects
					(font
						(size 1.27 1.27)
						(thickness 0.15)
					)
					(justify left bottom)
					(hide yes)
				)
			)
			(property "Datasheet" "https://www.infineon.com/dgdl/Infineon-S25FL256L_S25FL128L_256-MB_(32-MB)_128-MB_(16-MB)_3.0_V_FL-L_FLASH_MEMORY-DataSheet-v09_00-EN.pdf?fileId=8ac78c8c7d0d8da4017d0ed40e335224"
				(at 40.64 -12.7 0)
				(effects
					(font
						(size 1.27 1.27)
						(thickness 0.15)
					)
					(justify left bottom)
					(hide yes)
				)
			)
			(property "Description" "FLASH - NOR Memory IC 128Mb (16M x 8) SPI - Quad I/O, QPI 133 MHz 8-WSON (5x6)"
				(at 0 0 0)
				(effects
					(font
						(size 1.27 1.27)
					)
					(hide yes)
				)
			)
			(property "Manufacturer" "Cypress Semiconductor"
				(at 40.64 -15.24 0)
				(effects
					(font
						(size 1.27 1.27)
						(thickness 0.15)
					)
					(justify left bottom)
					(hide yes)
				)
			)
			(property "MPN" "S25FL128LAGNFA010"
				(at 40.64 -5.08 0)
				(effects
					(font
						(size 1.27 1.27)
						(thickness 0.15)
					)
					(justify left bottom)
				)
			)
			(property "Author" "Antmicro"
				(at 40.64 -17.78 0)
				(effects
					(font
						(size 1.27 1.27)
						(thickness 0.15)
					)
					(justify left bottom)
					(hide yes)
				)
			)
			(property "License" "Apache-2.0"
				(at 40.64 -20.32 0)
				(effects
					(font
						(size 1.27 1.27)
						(thickness 0.15)
					)
					(justify left bottom)
					(hide yes)
				)
			)
			(symbol "S25FL128LAGNFA010_1_1"
				(rectangle
					(start 2.54 2.54)
					(end 16.51 -20.32)
					(stroke
						(width 0.254)
						(type default)
					)
					(fill
						(type background)
					)
				)
				(pin input line
					(at 0 0 0)
					(length 2.54)
					(name "*CS"
						(effects
							(font
								(size 1.27 1.27)
							)
						)
					)
					(number "1"
						(effects
							(font
								(size 1.27 1.27)
							)
						)
					)
				)
				(pin input line
					(at 0 -2.54 0)
					(length 2.54)
					(name "SCK"
						(effects
							(font
								(size 1.27 1.27)
							)
						)
					)
					(number "6"
						(effects
							(font
								(size 1.27 1.27)
							)
						)
					)
				)
				(pin bidirectional line
					(at 0 -7.62 0)
					(length 2.54)
					(name "*HOLD/IO3"
						(effects
							(font
								(size 1.27 1.27)
							)
						)
					)
					(number "7"
						(effects
							(font
								(size 1.27 1.27)
							)
						)
					)
				)
				(pin bidirectional line
					(at 0 -10.16 0)
					(length 2.54)
					(name "*WP/IO2"
						(effects
							(font
								(size 1.27 1.27)
							)
						)
					)
					(number "3"
						(effects
							(font
								(size 1.27 1.27)
							)
						)
					)
				)
				(pin unspecified line
					(at 0 -12.7 0)
					(length 2.54)
					(name "EP"
						(effects
							(font
								(size 1.27 1.27)
							)
						)
					)
					(number "9"
						(effects
							(font
								(size 1.27 1.27)
							)
						)
					)
				)
				(pin bidirectional line
					(at 0 -15.24 0)
					(length 2.54)
					(name "SI/IO0"
						(effects
							(font
								(size 1.27 1.27)
							)
						)
					)
					(number "5"
						(effects
							(font
								(size 1.27 1.27)
							)
						)
					)
				)
				(pin bidirectional line
					(at 0 -17.78 0)
					(length 2.54)
					(name "SO/IO1"
						(effects
							(font
								(size 1.27 1.27)
							)
						)
					)
					(number "2"
						(effects
							(font
								(size 1.27 1.27)
							)
						)
					)
				)
				(pin power_in line
					(at 19.05 0 180)
					(length 2.54)
					(name "VCC"
						(effects
							(font
								(size 1.27 1.27)
							)
						)
					)
					(number "8"
						(effects
							(font
								(size 1.27 1.27)
							)
						)
					)
				)
				(pin power_in line
					(at 19.05 -17.78 180)
					(length 2.54)
					(name "VSS"
						(effects
							(font
								(size 1.27 1.27)
							)
						)
					)
					(number "4"
						(effects
							(font
								(size 1.27 1.27)
							)
						)
					)
				)
			)
		)
	(symbol "antmicroMemory:S27KL0641DABHI023"
			(exclude_from_sim no)
			(in_bom yes)
			(on_board yes)
			(property "Reference" "U"
				(at 45.72 -5.08 0)
				(effects
					(font
						(size 1.27 1.27)
						(thickness 0.15)
					)
					(justify left bottom)
				)
			)
			(property "Value" "S27KL0641DABHI023"
				(at 45.72 -7.62 0)
				(effects
					(font
						(size 1.27 1.27)
						(thickness 0.15)
					)
					(justify left bottom)
				)
			)
			(property "Footprint" "antmicro-footprints:FBGA-25-24_6x8mm_Layout5x5_P1mm"
				(at 45.72 -10.16 0)
				(effects
					(font
						(size 1.27 1.27)
						(thickness 0.15)
					)
					(justify left bottom)
					(hide yes)
				)
			)
			(property "Datasheet" "https://www.mouser.pl/datasheet/2/196/CYPR_S_A0011122227_1-3004854.pdf"
				(at 45.72 -12.7 0)
				(effects
					(font
						(size 1.27 1.27)
						(thickness 0.15)
					)
					(justify left bottom)
					(hide yes)
				)
			)
			(property "Description" ""
				(at 0 0 0)
				(effects
					(font
						(size 1.27 1.27)
					)
					(hide yes)
				)
			)
			(property "Manufacturer" "Cypress Semiconductor"
				(at 45.72 -15.24 0)
				(effects
					(font
						(size 1.27 1.27)
						(thickness 0.15)
					)
					(justify left bottom)
					(hide yes)
				)
			)
			(property "MPN" "S27KL0641DABHI023"
				(at 45.72 -17.78 0)
				(effects
					(font
						(size 1.27 1.27)
						(thickness 0.15)
					)
					(justify left bottom)
					(hide yes)
				)
			)
			(property "Author" "Antmicro"
				(at 45.72 -20.32 0)
				(effects
					(font
						(size 1.27 1.27)
						(thickness 0.15)
					)
					(justify left bottom)
					(hide yes)
				)
			)
			(property "License" "Apache-2.0"
				(at 45.72 -22.86 0)
				(effects
					(font
						(size 1.27 1.27)
						(thickness 0.15)
					)
					(justify left bottom)
					(hide yes)
				)
			)
			(symbol "S27KL0641DABHI023_1_1"
				(rectangle
					(start 2.54 2.54)
					(end 27.94 -40.64)
					(stroke
						(width 0.254)
						(type default)
					)
					(fill
						(type background)
					)
				)
				(rectangle
					(start 7.62 -1.27)
					(end 7.62 -1.27)
					(stroke
						(width 0.254)
						(type default)
					)
					(fill
						(type background)
					)
				)
				(rectangle
					(start 11.43 -38.1)
					(end 11.43 -38.1)
					(stroke
						(width 0.254)
						(type default)
					)
					(fill
						(type background)
					)
				)
				(pin input line
					(at 0 0 0)
					(length 2.54)
					(name "~{RESET}"
						(effects
							(font
								(size 1.27 1.27)
							)
						)
					)
					(number "A4"
						(effects
							(font
								(size 1.27 1.27)
							)
						)
					)
				)
				(pin input line
					(at 0 -2.54 0)
					(length 2.54)
					(name "~{CS}"
						(effects
							(font
								(size 1.27 1.27)
							)
						)
					)
					(number "A3"
						(effects
							(font
								(size 1.27 1.27)
							)
						)
					)
				)
				(pin input line
					(at 0 -7.62 0)
					(length 2.54)
					(name "CK+"
						(effects
							(font
								(size 1.27 1.27)
							)
						)
					)
					(number "B2"
						(effects
							(font
								(size 1.27 1.27)
							)
						)
					)
				)
				(pin input line
					(at 0 -10.16 0)
					(length 2.54)
					(name "CK-"
						(effects
							(font
								(size 1.27 1.27)
							)
						)
					)
					(number "B1"
						(effects
							(font
								(size 1.27 1.27)
							)
						)
					)
				)
				(pin bidirectional line
					(at 0 -15.24 0)
					(length 2.54)
					(name "DQ0"
						(effects
							(font
								(size 1.27 1.27)
							)
						)
					)
					(number "D3"
						(effects
							(font
								(size 1.27 1.27)
							)
						)
					)
				)
				(pin bidirectional line
					(at 0 -17.78 0)
					(length 2.54)
					(name "DQ1"
						(effects
							(font
								(size 1.27 1.27)
							)
						)
					)
					(number "D2"
						(effects
							(font
								(size 1.27 1.27)
							)
						)
					)
				)
				(pin bidirectional line
					(at 0 -20.32 0)
					(length 2.54)
					(name "DQ2"
						(effects
							(font
								(size 1.27 1.27)
							)
						)
					)
					(number "C4"
						(effects
							(font
								(size 1.27 1.27)
							)
						)
					)
				)
				(pin bidirectional line
					(at 0 -22.86 0)
					(length 2.54)
					(name "DQ3"
						(effects
							(font
								(size 1.27 1.27)
							)
						)
					)
					(number "D4"
						(effects
							(font
								(size 1.27 1.27)
							)
						)
					)
				)
				(pin bidirectional line
					(at 0 -25.4 0)
					(length 2.54)
					(name "DQ4"
						(effects
							(font
								(size 1.27 1.27)
							)
						)
					)
					(number "D5"
						(effects
							(font
								(size 1.27 1.27)
							)
						)
					)
				)
				(pin bidirectional line
					(at 0 -27.94 0)
					(length 2.54)
					(name "DQ5"
						(effects
							(font
								(size 1.27 1.27)
							)
						)
					)
					(number "E3"
						(effects
							(font
								(size 1.27 1.27)
							)
						)
					)
				)
				(pin bidirectional line
					(at 0 -30.48 0)
					(length 2.54)
					(name "DQ6"
						(effects
							(font
								(size 1.27 1.27)
							)
						)
					)
					(number "E2"
						(effects
							(font
								(size 1.27 1.27)
							)
						)
					)
				)
				(pin bidirectional line
					(at 0 -33.02 0)
					(length 2.54)
					(name "DQ7"
						(effects
							(font
								(size 1.27 1.27)
							)
						)
					)
					(number "E1"
						(effects
							(font
								(size 1.27 1.27)
							)
						)
					)
				)
				(pin bidirectional line
					(at 0 -38.1 0)
					(length 2.54)
					(name "RWDS"
						(effects
							(font
								(size 1.27 1.27)
							)
						)
					)
					(number "C3"
						(effects
							(font
								(size 1.27 1.27)
							)
						)
					)
				)
				(pin no_connect line
					(at 27.94 -30.48 180)
					(length 2.54)
					(hide yes)
					(name "NC"
						(effects
							(font
								(size 1.27 1.27)
							)
						)
					)
					(number "A2"
						(effects
							(font
								(size 1.27 1.27)
							)
						)
					)
				)
				(pin no_connect line
					(at 27.94 -30.48 180)
					(length 2.54)
					(hide yes)
					(name "NC"
						(effects
							(font
								(size 1.27 1.27)
							)
						)
					)
					(number "A5"
						(effects
							(font
								(size 1.27 1.27)
							)
						)
					)
				)
				(pin no_connect line
					(at 27.94 -30.48 180)
					(length 2.54)
					(hide yes)
					(name "NC"
						(effects
							(font
								(size 1.27 1.27)
							)
						)
					)
					(number "B5"
						(effects
							(font
								(size 1.27 1.27)
							)
						)
					)
				)
				(pin no_connect line
					(at 27.94 -30.48 180)
					(length 2.54)
					(hide yes)
					(name "NC"
						(effects
							(font
								(size 1.27 1.27)
							)
						)
					)
					(number "C2"
						(effects
							(font
								(size 1.27 1.27)
							)
						)
					)
				)
				(pin no_connect line
					(at 27.94 -30.48 180)
					(length 2.54)
					(hide yes)
					(name "NC"
						(effects
							(font
								(size 1.27 1.27)
							)
						)
					)
					(number "C5"
						(effects
							(font
								(size 1.27 1.27)
							)
						)
					)
				)
				(pin power_in line
					(at 30.48 0 180)
					(length 2.54)
					(name "VCC"
						(effects
							(font
								(size 1.27 1.27)
							)
						)
					)
					(number "B4"
						(effects
							(font
								(size 1.27 1.27)
							)
						)
					)
				)
				(pin power_in line
					(at 30.48 -2.54 180)
					(length 2.54)
					(name "VCCQ"
						(effects
							(font
								(size 1.27 1.27)
							)
						)
					)
					(number "D1"
						(effects
							(font
								(size 1.27 1.27)
							)
						)
					)
				)
				(pin passive line
					(at 30.48 -2.54 180)
					(length 2.54)
					(hide yes)
					(name "VCCQ"
						(effects
							(font
								(size 1.27 1.27)
							)
						)
					)
					(number "E4"
						(effects
							(font
								(size 1.27 1.27)
							)
						)
					)
				)
				(pin power_in line
					(at 30.48 -35.56 180)
					(length 2.54)
					(name "VSSQ"
						(effects
							(font
								(size 1.27 1.27)
							)
						)
					)
					(number "C1"
						(effects
							(font
								(size 1.27 1.27)
							)
						)
					)
				)
				(pin passive line
					(at 30.48 -35.56 180)
					(length 2.54)
					(hide yes)
					(name "VSSQ"
						(effects
							(font
								(size 1.27 1.27)
							)
						)
					)
					(number "E5"
						(effects
							(font
								(size 1.27 1.27)
							)
						)
					)
				)
				(pin power_in line
					(at 30.48 -38.1 180)
					(length 2.54)
					(name "VSS"
						(effects
							(font
								(size 1.27 1.27)
							)
						)
					)
					(number "B3"
						(effects
							(font
								(size 1.27 1.27)
							)
						)
					)
				)
			)
		)
	(symbol "antmicroMemoryConnectorsPCCardSockets:Bus_DDR4_SODIMM_TE_2309409"
			(exclude_from_sim no)
			(in_bom yes)
			(on_board yes)
			(property "Reference" "J"
				(at 36.83 -2.54 0)
				(effects
					(font
						(size 1.27 1.27)
						(thickness 0.15)
					)
					(justify left bottom)
				)
			)
			(property "Value" "Bus_DDR4_SODIMM_TE_2309409"
				(at 36.83 -7.62 0)
				(effects
					(font
						(size 1.27 1.27)
						(thickness 0.15)
					)
					(justify left bottom)
					(hide yes)
				)
			)
			(property "Footprint" "antmicro-footprints:Bus_DDR4_SODIMM_TE_2309409"
				(at 36.83 -10.16 0)
				(effects
					(font
						(size 1.27 1.27)
						(thickness 0.15)
					)
					(justify left bottom)
					(hide yes)
				)
			)
			(property "Datasheet" "https://www.mouser.com/datasheet/2/418/7/ENG_CD_2309409_5-2032664.pdf"
				(at 36.83 -12.7 0)
				(effects
					(font
						(size 1.27 1.27)
						(thickness 0.15)
					)
					(justify left bottom)
					(hide yes)
				)
			)
			(property "Description" "Memory Card Connector, DDR4, SODIMM, Cam-In Locking, 260 Contacts, Copper Alloy"
				(at 0 0 0)
				(effects
					(font
						(size 1.27 1.27)
					)
					(hide yes)
				)
			)
			(property "MPN" "2309409-1"
				(at 36.83 -5.08 0)
				(effects
					(font
						(size 1.27 1.27)
						(thickness 0.15)
					)
					(justify left bottom)
				)
			)
			(property "Manufacturer" "TE Connectivity"
				(at 36.83 -15.24 0)
				(effects
					(font
						(size 1.27 1.27)
						(thickness 0.15)
					)
					(justify left bottom)
					(hide yes)
				)
			)
			(property "Author" "Antmicro"
				(at 36.83 -17.78 0)
				(effects
					(font
						(size 1.27 1.27)
						(thickness 0.15)
					)
					(justify left bottom)
					(hide yes)
				)
			)
			(property "License" "Apache-2.0"
				(at 36.83 -20.32 0)
				(effects
					(font
						(size 1.27 1.27)
						(thickness 0.15)
					)
					(justify left bottom)
					(hide yes)
				)
			)
			(property "ki_locked" ""
				(at 0 0 0)
				(effects
					(font
						(size 1.27 1.27)
					)
				)
			)
			(property "ki_keywords" "DDR, SDRAM, CONNECTOR"
				(at 0 0 0)
				(effects
					(font
						(size 1.27 1.27)
					)
					(hide yes)
				)
			)
			(symbol "Bus_DDR4_SODIMM_TE_2309409_1_1"
				(rectangle
					(start 3.81 2.54)
					(end 19.05 -170.18)
					(stroke
						(width 0.254)
						(type default)
					)
					(fill
						(type background)
					)
				)
				(pin passive line
					(at 0 0 0)
					(length 3.81)
					(name "1"
						(effects
							(font
								(size 1.27 1.27)
							)
						)
					)
					(number "1"
						(effects
							(font
								(size 1.27 1.27)
							)
						)
					)
				)
				(pin passive line
					(at 0 -2.54 0)
					(length 3.81)
					(name "3"
						(effects
							(font
								(size 1.27 1.27)
							)
						)
					)
					(number "3"
						(effects
							(font
								(size 1.27 1.27)
							)
						)
					)
				)
				(pin passive line
					(at 0 -5.08 0)
					(length 3.81)
					(name "5"
						(effects
							(font
								(size 1.27 1.27)
							)
						)
					)
					(number "5"
						(effects
							(font
								(size 1.27 1.27)
							)
						)
					)
				)
				(pin passive line
					(at 0 -7.62 0)
					(length 3.81)
					(name "7"
						(effects
							(font
								(size 1.27 1.27)
							)
						)
					)
					(number "7"
						(effects
							(font
								(size 1.27 1.27)
							)
						)
					)
				)
				(pin passive line
					(at 0 -10.16 0)
					(length 3.81)
					(name "9"
						(effects
							(font
								(size 1.27 1.27)
							)
						)
					)
					(number "9"
						(effects
							(font
								(size 1.27 1.27)
							)
						)
					)
				)
				(pin passive line
					(at 0 -12.7 0)
					(length 3.81)
					(name "11"
						(effects
							(font
								(size 1.27 1.27)
							)
						)
					)
					(number "11"
						(effects
							(font
								(size 1.27 1.27)
							)
						)
					)
				)
				(pin passive line
					(at 0 -15.24 0)
					(length 3.81)
					(name "13"
						(effects
							(font
								(size 1.27 1.27)
							)
						)
					)
					(number "13"
						(effects
							(font
								(size 1.27 1.27)
							)
						)
					)
				)
				(pin passive line
					(at 0 -17.78 0)
					(length 3.81)
					(name "15"
						(effects
							(font
								(size 1.27 1.27)
							)
						)
					)
					(number "15"
						(effects
							(font
								(size 1.27 1.27)
							)
						)
					)
				)
				(pin passive line
					(at 0 -20.32 0)
					(length 3.81)
					(name "17"
						(effects
							(font
								(size 1.27 1.27)
							)
						)
					)
					(number "17"
						(effects
							(font
								(size 1.27 1.27)
							)
						)
					)
				)
				(pin passive line
					(at 0 -22.86 0)
					(length 3.81)
					(name "19"
						(effects
							(font
								(size 1.27 1.27)
							)
						)
					)
					(number "19"
						(effects
							(font
								(size 1.27 1.27)
							)
						)
					)
				)
				(pin passive line
					(at 0 -25.4 0)
					(length 3.81)
					(name "21"
						(effects
							(font
								(size 1.27 1.27)
							)
						)
					)
					(number "21"
						(effects
							(font
								(size 1.27 1.27)
							)
						)
					)
				)
				(pin passive line
					(at 0 -27.94 0)
					(length 3.81)
					(name "23"
						(effects
							(font
								(size 1.27 1.27)
							)
						)
					)
					(number "23"
						(effects
							(font
								(size 1.27 1.27)
							)
						)
					)
				)
				(pin passive line
					(at 0 -30.48 0)
					(length 3.81)
					(name "25"
						(effects
							(font
								(size 1.27 1.27)
							)
						)
					)
					(number "25"
						(effects
							(font
								(size 1.27 1.27)
							)
						)
					)
				)
				(pin passive line
					(at 0 -33.02 0)
					(length 3.81)
					(name "27"
						(effects
							(font
								(size 1.27 1.27)
							)
						)
					)
					(number "27"
						(effects
							(font
								(size 1.27 1.27)
							)
						)
					)
				)
				(pin passive line
					(at 0 -35.56 0)
					(length 3.81)
					(name "29"
						(effects
							(font
								(size 1.27 1.27)
							)
						)
					)
					(number "29"
						(effects
							(font
								(size 1.27 1.27)
							)
						)
					)
				)
				(pin passive line
					(at 0 -38.1 0)
					(length 3.81)
					(name "31"
						(effects
							(font
								(size 1.27 1.27)
							)
						)
					)
					(number "31"
						(effects
							(font
								(size 1.27 1.27)
							)
						)
					)
				)
				(pin passive line
					(at 0 -40.64 0)
					(length 3.81)
					(name "33"
						(effects
							(font
								(size 1.27 1.27)
							)
						)
					)
					(number "33"
						(effects
							(font
								(size 1.27 1.27)
							)
						)
					)
				)
				(pin passive line
					(at 0 -43.18 0)
					(length 3.81)
					(name "35"
						(effects
							(font
								(size 1.27 1.27)
							)
						)
					)
					(number "35"
						(effects
							(font
								(size 1.27 1.27)
							)
						)
					)
				)
				(pin passive line
					(at 0 -45.72 0)
					(length 3.81)
					(name "37"
						(effects
							(font
								(size 1.27 1.27)
							)
						)
					)
					(number "37"
						(effects
							(font
								(size 1.27 1.27)
							)
						)
					)
				)
				(pin passive line
					(at 0 -48.26 0)
					(length 3.81)
					(name "39"
						(effects
							(font
								(size 1.27 1.27)
							)
						)
					)
					(number "39"
						(effects
							(font
								(size 1.27 1.27)
							)
						)
					)
				)
				(pin passive line
					(at 0 -50.8 0)
					(length 3.81)
					(name "41"
						(effects
							(font
								(size 1.27 1.27)
							)
						)
					)
					(number "41"
						(effects
							(font
								(size 1.27 1.27)
							)
						)
					)
				)
				(pin passive line
					(at 0 -53.34 0)
					(length 3.81)
					(name "43"
						(effects
							(font
								(size 1.27 1.27)
							)
						)
					)
					(number "43"
						(effects
							(font
								(size 1.27 1.27)
							)
						)
					)
				)
				(pin passive line
					(at 0 -55.88 0)
					(length 3.81)
					(name "45"
						(effects
							(font
								(size 1.27 1.27)
							)
						)
					)
					(number "45"
						(effects
							(font
								(size 1.27 1.27)
							)
						)
					)
				)
				(pin passive line
					(at 0 -58.42 0)
					(length 3.81)
					(name "47"
						(effects
							(font
								(size 1.27 1.27)
							)
						)
					)
					(number "47"
						(effects
							(font
								(size 1.27 1.27)
							)
						)
					)
				)
				(pin passive line
					(at 0 -60.96 0)
					(length 3.81)
					(name "49"
						(effects
							(font
								(size 1.27 1.27)
							)
						)
					)
					(number "49"
						(effects
							(font
								(size 1.27 1.27)
							)
						)
					)
				)
				(pin passive line
					(at 0 -63.5 0)
					(length 3.81)
					(name "51"
						(effects
							(font
								(size 1.27 1.27)
							)
						)
					)
					(number "51"
						(effects
							(font
								(size 1.27 1.27)
							)
						)
					)
				)
				(pin passive line
					(at 0 -66.04 0)
					(length 3.81)
					(name "53"
						(effects
							(font
								(size 1.27 1.27)
							)
						)
					)
					(number "53"
						(effects
							(font
								(size 1.27 1.27)
							)
						)
					)
				)
				(pin passive line
					(at 0 -68.58 0)
					(length 3.81)
					(name "55"
						(effects
							(font
								(size 1.27 1.27)
							)
						)
					)
					(number "55"
						(effects
							(font
								(size 1.27 1.27)
							)
						)
					)
				)
				(pin passive line
					(at 0 -71.12 0)
					(length 3.81)
					(name "57"
						(effects
							(font
								(size 1.27 1.27)
							)
						)
					)
					(number "57"
						(effects
							(font
								(size 1.27 1.27)
							)
						)
					)
				)
				(pin passive line
					(at 0 -73.66 0)
					(length 3.81)
					(name "59"
						(effects
							(font
								(size 1.27 1.27)
							)
						)
					)
					(number "59"
						(effects
							(font
								(size 1.27 1.27)
							)
						)
					)
				)
				(pin passive line
					(at 0 -76.2 0)
					(length 3.81)
					(name "61"
						(effects
							(font
								(size 1.27 1.27)
							)
						)
					)
					(number "61"
						(effects
							(font
								(size 1.27 1.27)
							)
						)
					)
				)
				(pin passive line
					(at 0 -78.74 0)
					(length 3.81)
					(name "63"
						(effects
							(font
								(size 1.27 1.27)
							)
						)
					)
					(number "63"
						(effects
							(font
								(size 1.27 1.27)
							)
						)
					)
				)
				(pin passive line
					(at 0 -81.28 0)
					(length 3.81)
					(name "65"
						(effects
							(font
								(size 1.27 1.27)
							)
						)
					)
					(number "65"
						(effects
							(font
								(size 1.27 1.27)
							)
						)
					)
				)
				(pin passive line
					(at 0 -83.82 0)
					(length 3.81)
					(name "67"
						(effects
							(font
								(size 1.27 1.27)
							)
						)
					)
					(number "67"
						(effects
							(font
								(size 1.27 1.27)
							)
						)
					)
				)
				(pin passive line
					(at 0 -86.36 0)
					(length 3.81)
					(name "69"
						(effects
							(font
								(size 1.27 1.27)
							)
						)
					)
					(number "69"
						(effects
							(font
								(size 1.27 1.27)
							)
						)
					)
				)
				(pin passive line
					(at 0 -88.9 0)
					(length 3.81)
					(name "71"
						(effects
							(font
								(size 1.27 1.27)
							)
						)
					)
					(number "71"
						(effects
							(font
								(size 1.27 1.27)
							)
						)
					)
				)
				(pin passive line
					(at 0 -91.44 0)
					(length 3.81)
					(name "73"
						(effects
							(font
								(size 1.27 1.27)
							)
						)
					)
					(number "73"
						(effects
							(font
								(size 1.27 1.27)
							)
						)
					)
				)
				(pin passive line
					(at 0 -93.98 0)
					(length 3.81)
					(name "75"
						(effects
							(font
								(size 1.27 1.27)
							)
						)
					)
					(number "75"
						(effects
							(font
								(size 1.27 1.27)
							)
						)
					)
				)
				(pin passive line
					(at 0 -96.52 0)
					(length 3.81)
					(name "77"
						(effects
							(font
								(size 1.27 1.27)
							)
						)
					)
					(number "77"
						(effects
							(font
								(size 1.27 1.27)
							)
						)
					)
				)
				(pin passive line
					(at 0 -99.06 0)
					(length 3.81)
					(name "79"
						(effects
							(font
								(size 1.27 1.27)
							)
						)
					)
					(number "79"
						(effects
							(font
								(size 1.27 1.27)
							)
						)
					)
				)
				(pin passive line
					(at 0 -101.6 0)
					(length 3.81)
					(name "81"
						(effects
							(font
								(size 1.27 1.27)
							)
						)
					)
					(number "81"
						(effects
							(font
								(size 1.27 1.27)
							)
						)
					)
				)
				(pin passive line
					(at 0 -104.14 0)
					(length 3.81)
					(name "83"
						(effects
							(font
								(size 1.27 1.27)
							)
						)
					)
					(number "83"
						(effects
							(font
								(size 1.27 1.27)
							)
						)
					)
				)
				(pin passive line
					(at 0 -106.68 0)
					(length 3.81)
					(name "85"
						(effects
							(font
								(size 1.27 1.27)
							)
						)
					)
					(number "85"
						(effects
							(font
								(size 1.27 1.27)
							)
						)
					)
				)
				(pin passive line
					(at 0 -109.22 0)
					(length 3.81)
					(name "87"
						(effects
							(font
								(size 1.27 1.27)
							)
						)
					)
					(number "87"
						(effects
							(font
								(size 1.27 1.27)
							)
						)
					)
				)
				(pin passive line
					(at 0 -111.76 0)
					(length 3.81)
					(name "89"
						(effects
							(font
								(size 1.27 1.27)
							)
						)
					)
					(number "89"
						(effects
							(font
								(size 1.27 1.27)
							)
						)
					)
				)
				(pin passive line
					(at 0 -114.3 0)
					(length 3.81)
					(name "91"
						(effects
							(font
								(size 1.27 1.27)
							)
						)
					)
					(number "91"
						(effects
							(font
								(size 1.27 1.27)
							)
						)
					)
				)
				(pin passive line
					(at 0 -116.84 0)
					(length 3.81)
					(name "93"
						(effects
							(font
								(size 1.27 1.27)
							)
						)
					)
					(number "93"
						(effects
							(font
								(size 1.27 1.27)
							)
						)
					)
				)
				(pin passive line
					(at 0 -119.38 0)
					(length 3.81)
					(name "95"
						(effects
							(font
								(size 1.27 1.27)
							)
						)
					)
					(number "95"
						(effects
							(font
								(size 1.27 1.27)
							)
						)
					)
				)
				(pin passive line
					(at 0 -121.92 0)
					(length 3.81)
					(name "97"
						(effects
							(font
								(size 1.27 1.27)
							)
						)
					)
					(number "97"
						(effects
							(font
								(size 1.27 1.27)
							)
						)
					)
				)
				(pin passive line
					(at 0 -124.46 0)
					(length 3.81)
					(name "99"
						(effects
							(font
								(size 1.27 1.27)
							)
						)
					)
					(number "99"
						(effects
							(font
								(size 1.27 1.27)
							)
						)
					)
				)
				(pin passive line
					(at 0 -127 0)
					(length 3.81)
					(name "101"
						(effects
							(font
								(size 1.27 1.27)
							)
						)
					)
					(number "101"
						(effects
							(font
								(size 1.27 1.27)
							)
						)
					)
				)
				(pin passive line
					(at 0 -129.54 0)
					(length 3.81)
					(name "103"
						(effects
							(font
								(size 1.27 1.27)
							)
						)
					)
					(number "103"
						(effects
							(font
								(size 1.27 1.27)
							)
						)
					)
				)
				(pin passive line
					(at 0 -132.08 0)
					(length 3.81)
					(name "105"
						(effects
							(font
								(size 1.27 1.27)
							)
						)
					)
					(number "105"
						(effects
							(font
								(size 1.27 1.27)
							)
						)
					)
				)
				(pin passive line
					(at 0 -134.62 0)
					(length 3.81)
					(name "107"
						(effects
							(font
								(size 1.27 1.27)
							)
						)
					)
					(number "107"
						(effects
							(font
								(size 1.27 1.27)
							)
						)
					)
				)
				(pin passive line
					(at 0 -137.16 0)
					(length 3.81)
					(name "109"
						(effects
							(font
								(size 1.27 1.27)
							)
						)
					)
					(number "109"
						(effects
							(font
								(size 1.27 1.27)
							)
						)
					)
				)
				(pin passive line
					(at 0 -139.7 0)
					(length 3.81)
					(name "111"
						(effects
							(font
								(size 1.27 1.27)
							)
						)
					)
					(number "111"
						(effects
							(font
								(size 1.27 1.27)
							)
						)
					)
				)
				(pin passive line
					(at 0 -142.24 0)
					(length 3.81)
					(name "113"
						(effects
							(font
								(size 1.27 1.27)
							)
						)
					)
					(number "113"
						(effects
							(font
								(size 1.27 1.27)
							)
						)
					)
				)
				(pin passive line
					(at 0 -144.78 0)
					(length 3.81)
					(name "115"
						(effects
							(font
								(size 1.27 1.27)
							)
						)
					)
					(number "115"
						(effects
							(font
								(size 1.27 1.27)
							)
						)
					)
				)
				(pin passive line
					(at 0 -147.32 0)
					(length 3.81)
					(name "117"
						(effects
							(font
								(size 1.27 1.27)
							)
						)
					)
					(number "117"
						(effects
							(font
								(size 1.27 1.27)
							)
						)
					)
				)
				(pin passive line
					(at 0 -149.86 0)
					(length 3.81)
					(name "119"
						(effects
							(font
								(size 1.27 1.27)
							)
						)
					)
					(number "119"
						(effects
							(font
								(size 1.27 1.27)
							)
						)
					)
				)
				(pin passive line
					(at 0 -152.4 0)
					(length 3.81)
					(name "121"
						(effects
							(font
								(size 1.27 1.27)
							)
						)
					)
					(number "121"
						(effects
							(font
								(size 1.27 1.27)
							)
						)
					)
				)
				(pin passive line
					(at 0 -154.94 0)
					(length 3.81)
					(name "123"
						(effects
							(font
								(size 1.27 1.27)
							)
						)
					)
					(number "123"
						(effects
							(font
								(size 1.27 1.27)
							)
						)
					)
				)
				(pin passive line
					(at 0 -157.48 0)
					(length 3.81)
					(name "125"
						(effects
							(font
								(size 1.27 1.27)
							)
						)
					)
					(number "125"
						(effects
							(font
								(size 1.27 1.27)
							)
						)
					)
				)
				(pin passive line
					(at 0 -160.02 0)
					(length 3.81)
					(name "127"
						(effects
							(font
								(size 1.27 1.27)
							)
						)
					)
					(number "127"
						(effects
							(font
								(size 1.27 1.27)
							)
						)
					)
				)
				(pin passive line
					(at 0 -162.56 0)
					(length 3.81)
					(name "129"
						(effects
							(font
								(size 1.27 1.27)
							)
						)
					)
					(number "129"
						(effects
							(font
								(size 1.27 1.27)
							)
						)
					)
				)
				(pin passive line
					(at 22.86 0 180)
					(length 3.81)
					(name "2"
						(effects
							(font
								(size 1.27 1.27)
							)
						)
					)
					(number "2"
						(effects
							(font
								(size 1.27 1.27)
							)
						)
					)
				)
				(pin passive line
					(at 22.86 -2.54 180)
					(length 3.81)
					(name "4"
						(effects
							(font
								(size 1.27 1.27)
							)
						)
					)
					(number "4"
						(effects
							(font
								(size 1.27 1.27)
							)
						)
					)
				)
				(pin passive line
					(at 22.86 -5.08 180)
					(length 3.81)
					(name "6"
						(effects
							(font
								(size 1.27 1.27)
							)
						)
					)
					(number "6"
						(effects
							(font
								(size 1.27 1.27)
							)
						)
					)
				)
				(pin passive line
					(at 22.86 -7.62 180)
					(length 3.81)
					(name "8"
						(effects
							(font
								(size 1.27 1.27)
							)
						)
					)
					(number "8"
						(effects
							(font
								(size 1.27 1.27)
							)
						)
					)
				)
				(pin passive line
					(at 22.86 -10.16 180)
					(length 3.81)
					(name "10"
						(effects
							(font
								(size 1.27 1.27)
							)
						)
					)
					(number "10"
						(effects
							(font
								(size 1.27 1.27)
							)
						)
					)
				)
				(pin passive line
					(at 22.86 -12.7 180)
					(length 3.81)
					(name "12"
						(effects
							(font
								(size 1.27 1.27)
							)
						)
					)
					(number "12"
						(effects
							(font
								(size 1.27 1.27)
							)
						)
					)
				)
				(pin passive line
					(at 22.86 -15.24 180)
					(length 3.81)
					(name "14"
						(effects
							(font
								(size 1.27 1.27)
							)
						)
					)
					(number "14"
						(effects
							(font
								(size 1.27 1.27)
							)
						)
					)
				)
				(pin passive line
					(at 22.86 -17.78 180)
					(length 3.81)
					(name "16"
						(effects
							(font
								(size 1.27 1.27)
							)
						)
					)
					(number "16"
						(effects
							(font
								(size 1.27 1.27)
							)
						)
					)
				)
				(pin passive line
					(at 22.86 -20.32 180)
					(length 3.81)
					(name "18"
						(effects
							(font
								(size 1.27 1.27)
							)
						)
					)
					(number "18"
						(effects
							(font
								(size 1.27 1.27)
							)
						)
					)
				)
				(pin passive line
					(at 22.86 -22.86 180)
					(length 3.81)
					(name "20"
						(effects
							(font
								(size 1.27 1.27)
							)
						)
					)
					(number "20"
						(effects
							(font
								(size 1.27 1.27)
							)
						)
					)
				)
				(pin passive line
					(at 22.86 -25.4 180)
					(length 3.81)
					(name "22"
						(effects
							(font
								(size 1.27 1.27)
							)
						)
					)
					(number "22"
						(effects
							(font
								(size 1.27 1.27)
							)
						)
					)
				)
				(pin passive line
					(at 22.86 -27.94 180)
					(length 3.81)
					(name "24"
						(effects
							(font
								(size 1.27 1.27)
							)
						)
					)
					(number "24"
						(effects
							(font
								(size 1.27 1.27)
							)
						)
					)
				)
				(pin passive line
					(at 22.86 -30.48 180)
					(length 3.81)
					(name "26"
						(effects
							(font
								(size 1.27 1.27)
							)
						)
					)
					(number "26"
						(effects
							(font
								(size 1.27 1.27)
							)
						)
					)
				)
				(pin passive line
					(at 22.86 -33.02 180)
					(length 3.81)
					(name "28"
						(effects
							(font
								(size 1.27 1.27)
							)
						)
					)
					(number "28"
						(effects
							(font
								(size 1.27 1.27)
							)
						)
					)
				)
				(pin passive line
					(at 22.86 -35.56 180)
					(length 3.81)
					(name "30"
						(effects
							(font
								(size 1.27 1.27)
							)
						)
					)
					(number "30"
						(effects
							(font
								(size 1.27 1.27)
							)
						)
					)
				)
				(pin passive line
					(at 22.86 -38.1 180)
					(length 3.81)
					(name "32"
						(effects
							(font
								(size 1.27 1.27)
							)
						)
					)
					(number "32"
						(effects
							(font
								(size 1.27 1.27)
							)
						)
					)
				)
				(pin passive line
					(at 22.86 -40.64 180)
					(length 3.81)
					(name "34"
						(effects
							(font
								(size 1.27 1.27)
							)
						)
					)
					(number "34"
						(effects
							(font
								(size 1.27 1.27)
							)
						)
					)
				)
				(pin passive line
					(at 22.86 -43.18 180)
					(length 3.81)
					(name "36"
						(effects
							(font
								(size 1.27 1.27)
							)
						)
					)
					(number "36"
						(effects
							(font
								(size 1.27 1.27)
							)
						)
					)
				)
				(pin passive line
					(at 22.86 -45.72 180)
					(length 3.81)
					(name "38"
						(effects
							(font
								(size 1.27 1.27)
							)
						)
					)
					(number "38"
						(effects
							(font
								(size 1.27 1.27)
							)
						)
					)
				)
				(pin passive line
					(at 22.86 -48.26 180)
					(length 3.81)
					(name "40"
						(effects
							(font
								(size 1.27 1.27)
							)
						)
					)
					(number "40"
						(effects
							(font
								(size 1.27 1.27)
							)
						)
					)
				)
				(pin passive line
					(at 22.86 -50.8 180)
					(length 3.81)
					(name "42"
						(effects
							(font
								(size 1.27 1.27)
							)
						)
					)
					(number "42"
						(effects
							(font
								(size 1.27 1.27)
							)
						)
					)
				)
				(pin passive line
					(at 22.86 -53.34 180)
					(length 3.81)
					(name "44"
						(effects
							(font
								(size 1.27 1.27)
							)
						)
					)
					(number "44"
						(effects
							(font
								(size 1.27 1.27)
							)
						)
					)
				)
				(pin passive line
					(at 22.86 -55.88 180)
					(length 3.81)
					(name "46"
						(effects
							(font
								(size 1.27 1.27)
							)
						)
					)
					(number "46"
						(effects
							(font
								(size 1.27 1.27)
							)
						)
					)
				)
				(pin passive line
					(at 22.86 -58.42 180)
					(length 3.81)
					(name "48"
						(effects
							(font
								(size 1.27 1.27)
							)
						)
					)
					(number "48"
						(effects
							(font
								(size 1.27 1.27)
							)
						)
					)
				)
				(pin passive line
					(at 22.86 -60.96 180)
					(length 3.81)
					(name "50"
						(effects
							(font
								(size 1.27 1.27)
							)
						)
					)
					(number "50"
						(effects
							(font
								(size 1.27 1.27)
							)
						)
					)
				)
				(pin passive line
					(at 22.86 -63.5 180)
					(length 3.81)
					(name "52"
						(effects
							(font
								(size 1.27 1.27)
							)
						)
					)
					(number "52"
						(effects
							(font
								(size 1.27 1.27)
							)
						)
					)
				)
				(pin passive line
					(at 22.86 -66.04 180)
					(length 3.81)
					(name "54"
						(effects
							(font
								(size 1.27 1.27)
							)
						)
					)
					(number "54"
						(effects
							(font
								(size 1.27 1.27)
							)
						)
					)
				)
				(pin passive line
					(at 22.86 -68.58 180)
					(length 3.81)
					(name "56"
						(effects
							(font
								(size 1.27 1.27)
							)
						)
					)
					(number "56"
						(effects
							(font
								(size 1.27 1.27)
							)
						)
					)
				)
				(pin passive line
					(at 22.86 -71.12 180)
					(length 3.81)
					(name "58"
						(effects
							(font
								(size 1.27 1.27)
							)
						)
					)
					(number "58"
						(effects
							(font
								(size 1.27 1.27)
							)
						)
					)
				)
				(pin passive line
					(at 22.86 -73.66 180)
					(length 3.81)
					(name "60"
						(effects
							(font
								(size 1.27 1.27)
							)
						)
					)
					(number "60"
						(effects
							(font
								(size 1.27 1.27)
							)
						)
					)
				)
				(pin passive line
					(at 22.86 -76.2 180)
					(length 3.81)
					(name "62"
						(effects
							(font
								(size 1.27 1.27)
							)
						)
					)
					(number "62"
						(effects
							(font
								(size 1.27 1.27)
							)
						)
					)
				)
				(pin passive line
					(at 22.86 -78.74 180)
					(length 3.81)
					(name "64"
						(effects
							(font
								(size 1.27 1.27)
							)
						)
					)
					(number "64"
						(effects
							(font
								(size 1.27 1.27)
							)
						)
					)
				)
				(pin passive line
					(at 22.86 -81.28 180)
					(length 3.81)
					(name "66"
						(effects
							(font
								(size 1.27 1.27)
							)
						)
					)
					(number "66"
						(effects
							(font
								(size 1.27 1.27)
							)
						)
					)
				)
				(pin passive line
					(at 22.86 -83.82 180)
					(length 3.81)
					(name "68"
						(effects
							(font
								(size 1.27 1.27)
							)
						)
					)
					(number "68"
						(effects
							(font
								(size 1.27 1.27)
							)
						)
					)
				)
				(pin passive line
					(at 22.86 -86.36 180)
					(length 3.81)
					(name "70"
						(effects
							(font
								(size 1.27 1.27)
							)
						)
					)
					(number "70"
						(effects
							(font
								(size 1.27 1.27)
							)
						)
					)
				)
				(pin passive line
					(at 22.86 -88.9 180)
					(length 3.81)
					(name "72"
						(effects
							(font
								(size 1.27 1.27)
							)
						)
					)
					(number "72"
						(effects
							(font
								(size 1.27 1.27)
							)
						)
					)
				)
				(pin passive line
					(at 22.86 -91.44 180)
					(length 3.81)
					(name "74"
						(effects
							(font
								(size 1.27 1.27)
							)
						)
					)
					(number "74"
						(effects
							(font
								(size 1.27 1.27)
							)
						)
					)
				)
				(pin passive line
					(at 22.86 -93.98 180)
					(length 3.81)
					(name "76"
						(effects
							(font
								(size 1.27 1.27)
							)
						)
					)
					(number "76"
						(effects
							(font
								(size 1.27 1.27)
							)
						)
					)
				)
				(pin passive line
					(at 22.86 -96.52 180)
					(length 3.81)
					(name "78"
						(effects
							(font
								(size 1.27 1.27)
							)
						)
					)
					(number "78"
						(effects
							(font
								(size 1.27 1.27)
							)
						)
					)
				)
				(pin passive line
					(at 22.86 -99.06 180)
					(length 3.81)
					(name "80"
						(effects
							(font
								(size 1.27 1.27)
							)
						)
					)
					(number "80"
						(effects
							(font
								(size 1.27 1.27)
							)
						)
					)
				)
				(pin passive line
					(at 22.86 -101.6 180)
					(length 3.81)
					(name "82"
						(effects
							(font
								(size 1.27 1.27)
							)
						)
					)
					(number "82"
						(effects
							(font
								(size 1.27 1.27)
							)
						)
					)
				)
				(pin passive line
					(at 22.86 -104.14 180)
					(length 3.81)
					(name "84"
						(effects
							(font
								(size 1.27 1.27)
							)
						)
					)
					(number "84"
						(effects
							(font
								(size 1.27 1.27)
							)
						)
					)
				)
				(pin passive line
					(at 22.86 -106.68 180)
					(length 3.81)
					(name "86"
						(effects
							(font
								(size 1.27 1.27)
							)
						)
					)
					(number "86"
						(effects
							(font
								(size 1.27 1.27)
							)
						)
					)
				)
				(pin passive line
					(at 22.86 -109.22 180)
					(length 3.81)
					(name "88"
						(effects
							(font
								(size 1.27 1.27)
							)
						)
					)
					(number "88"
						(effects
							(font
								(size 1.27 1.27)
							)
						)
					)
				)
				(pin passive line
					(at 22.86 -111.76 180)
					(length 3.81)
					(name "90"
						(effects
							(font
								(size 1.27 1.27)
							)
						)
					)
					(number "90"
						(effects
							(font
								(size 1.27 1.27)
							)
						)
					)
				)
				(pin passive line
					(at 22.86 -114.3 180)
					(length 3.81)
					(name "92"
						(effects
							(font
								(size 1.27 1.27)
							)
						)
					)
					(number "92"
						(effects
							(font
								(size 1.27 1.27)
							)
						)
					)
				)
				(pin passive line
					(at 22.86 -116.84 180)
					(length 3.81)
					(name "94"
						(effects
							(font
								(size 1.27 1.27)
							)
						)
					)
					(number "94"
						(effects
							(font
								(size 1.27 1.27)
							)
						)
					)
				)
				(pin passive line
					(at 22.86 -119.38 180)
					(length 3.81)
					(name "96"
						(effects
							(font
								(size 1.27 1.27)
							)
						)
					)
					(number "96"
						(effects
							(font
								(size 1.27 1.27)
							)
						)
					)
				)
				(pin passive line
					(at 22.86 -121.92 180)
					(length 3.81)
					(name "98"
						(effects
							(font
								(size 1.27 1.27)
							)
						)
					)
					(number "98"
						(effects
							(font
								(size 1.27 1.27)
							)
						)
					)
				)
				(pin passive line
					(at 22.86 -124.46 180)
					(length 3.81)
					(name "100"
						(effects
							(font
								(size 1.27 1.27)
							)
						)
					)
					(number "100"
						(effects
							(font
								(size 1.27 1.27)
							)
						)
					)
				)
				(pin passive line
					(at 22.86 -127 180)
					(length 3.81)
					(name "102"
						(effects
							(font
								(size 1.27 1.27)
							)
						)
					)
					(number "102"
						(effects
							(font
								(size 1.27 1.27)
							)
						)
					)
				)
				(pin passive line
					(at 22.86 -129.54 180)
					(length 3.81)
					(name "104"
						(effects
							(font
								(size 1.27 1.27)
							)
						)
					)
					(number "104"
						(effects
							(font
								(size 1.27 1.27)
							)
						)
					)
				)
				(pin passive line
					(at 22.86 -132.08 180)
					(length 3.81)
					(name "106"
						(effects
							(font
								(size 1.27 1.27)
							)
						)
					)
					(number "106"
						(effects
							(font
								(size 1.27 1.27)
							)
						)
					)
				)
				(pin passive line
					(at 22.86 -134.62 180)
					(length 3.81)
					(name "108"
						(effects
							(font
								(size 1.27 1.27)
							)
						)
					)
					(number "108"
						(effects
							(font
								(size 1.27 1.27)
							)
						)
					)
				)
				(pin passive line
					(at 22.86 -137.16 180)
					(length 3.81)
					(name "110"
						(effects
							(font
								(size 1.27 1.27)
							)
						)
					)
					(number "110"
						(effects
							(font
								(size 1.27 1.27)
							)
						)
					)
				)
				(pin passive line
					(at 22.86 -139.7 180)
					(length 3.81)
					(name "112"
						(effects
							(font
								(size 1.27 1.27)
							)
						)
					)
					(number "112"
						(effects
							(font
								(size 1.27 1.27)
							)
						)
					)
				)
				(pin passive line
					(at 22.86 -142.24 180)
					(length 3.81)
					(name "114"
						(effects
							(font
								(size 1.27 1.27)
							)
						)
					)
					(number "114"
						(effects
							(font
								(size 1.27 1.27)
							)
						)
					)
				)
				(pin passive line
					(at 22.86 -144.78 180)
					(length 3.81)
					(name "116"
						(effects
							(font
								(size 1.27 1.27)
							)
						)
					)
					(number "116"
						(effects
							(font
								(size 1.27 1.27)
							)
						)
					)
				)
				(pin passive line
					(at 22.86 -147.32 180)
					(length 3.81)
					(name "118"
						(effects
							(font
								(size 1.27 1.27)
							)
						)
					)
					(number "118"
						(effects
							(font
								(size 1.27 1.27)
							)
						)
					)
				)
				(pin passive line
					(at 22.86 -149.86 180)
					(length 3.81)
					(name "120"
						(effects
							(font
								(size 1.27 1.27)
							)
						)
					)
					(number "120"
						(effects
							(font
								(size 1.27 1.27)
							)
						)
					)
				)
				(pin passive line
					(at 22.86 -152.4 180)
					(length 3.81)
					(name "122"
						(effects
							(font
								(size 1.27 1.27)
							)
						)
					)
					(number "122"
						(effects
							(font
								(size 1.27 1.27)
							)
						)
					)
				)
				(pin passive line
					(at 22.86 -154.94 180)
					(length 3.81)
					(name "124"
						(effects
							(font
								(size 1.27 1.27)
							)
						)
					)
					(number "124"
						(effects
							(font
								(size 1.27 1.27)
							)
						)
					)
				)
				(pin passive line
					(at 22.86 -157.48 180)
					(length 3.81)
					(name "126"
						(effects
							(font
								(size 1.27 1.27)
							)
						)
					)
					(number "126"
						(effects
							(font
								(size 1.27 1.27)
							)
						)
					)
				)
				(pin passive line
					(at 22.86 -160.02 180)
					(length 3.81)
					(name "128"
						(effects
							(font
								(size 1.27 1.27)
							)
						)
					)
					(number "128"
						(effects
							(font
								(size 1.27 1.27)
							)
						)
					)
				)
				(pin passive line
					(at 22.86 -162.56 180)
					(length 3.81)
					(name "130"
						(effects
							(font
								(size 1.27 1.27)
							)
						)
					)
					(number "130"
						(effects
							(font
								(size 1.27 1.27)
							)
						)
					)
				)
				(pin passive line
					(at 22.86 -167.64 180)
					(length 3.81)
					(name "SHIELD"
						(effects
							(font
								(size 1.27 1.27)
							)
						)
					)
					(number "S1"
						(effects
							(font
								(size 1.27 1.27)
							)
						)
					)
				)
				(pin passive line
					(at 22.86 -167.64 180)
					(length 3.81)
					(hide yes)
					(name "SHIELD"
						(effects
							(font
								(size 1.27 1.27)
							)
						)
					)
					(number "S2"
						(effects
							(font
								(size 1.27 1.27)
							)
						)
					)
				)
			)
			(symbol "Bus_DDR4_SODIMM_TE_2309409_2_1"
				(rectangle
					(start 3.81 2.54)
					(end 19.05 -165.1)
					(stroke
						(width 0.254)
						(type default)
					)
					(fill
						(type background)
					)
				)
				(pin passive line
					(at 0 0 0)
					(length 3.81)
					(name "131"
						(effects
							(font
								(size 1.27 1.27)
							)
						)
					)
					(number "131"
						(effects
							(font
								(size 1.27 1.27)
							)
						)
					)
				)
				(pin passive line
					(at 0 -2.54 0)
					(length 3.81)
					(name "133"
						(effects
							(font
								(size 1.27 1.27)
							)
						)
					)
					(number "133"
						(effects
							(font
								(size 1.27 1.27)
							)
						)
					)
				)
				(pin passive line
					(at 0 -5.08 0)
					(length 3.81)
					(name "135"
						(effects
							(font
								(size 1.27 1.27)
							)
						)
					)
					(number "135"
						(effects
							(font
								(size 1.27 1.27)
							)
						)
					)
				)
				(pin passive line
					(at 0 -7.62 0)
					(length 3.81)
					(name "137"
						(effects
							(font
								(size 1.27 1.27)
							)
						)
					)
					(number "137"
						(effects
							(font
								(size 1.27 1.27)
							)
						)
					)
				)
				(pin passive line
					(at 0 -10.16 0)
					(length 3.81)
					(name "139"
						(effects
							(font
								(size 1.27 1.27)
							)
						)
					)
					(number "139"
						(effects
							(font
								(size 1.27 1.27)
							)
						)
					)
				)
				(pin passive line
					(at 0 -12.7 0)
					(length 3.81)
					(name "141"
						(effects
							(font
								(size 1.27 1.27)
							)
						)
					)
					(number "141"
						(effects
							(font
								(size 1.27 1.27)
							)
						)
					)
				)
				(pin passive line
					(at 0 -15.24 0)
					(length 3.81)
					(name "143"
						(effects
							(font
								(size 1.27 1.27)
							)
						)
					)
					(number "143"
						(effects
							(font
								(size 1.27 1.27)
							)
						)
					)
				)
				(pin passive line
					(at 0 -17.78 0)
					(length 3.81)
					(name "145"
						(effects
							(font
								(size 1.27 1.27)
							)
						)
					)
					(number "145"
						(effects
							(font
								(size 1.27 1.27)
							)
						)
					)
				)
				(pin passive line
					(at 0 -20.32 0)
					(length 3.81)
					(name "147"
						(effects
							(font
								(size 1.27 1.27)
							)
						)
					)
					(number "147"
						(effects
							(font
								(size 1.27 1.27)
							)
						)
					)
				)
				(pin passive line
					(at 0 -22.86 0)
					(length 3.81)
					(name "149"
						(effects
							(font
								(size 1.27 1.27)
							)
						)
					)
					(number "149"
						(effects
							(font
								(size 1.27 1.27)
							)
						)
					)
				)
				(pin passive line
					(at 0 -25.4 0)
					(length 3.81)
					(name "151"
						(effects
							(font
								(size 1.27 1.27)
							)
						)
					)
					(number "151"
						(effects
							(font
								(size 1.27 1.27)
							)
						)
					)
				)
				(pin passive line
					(at 0 -27.94 0)
					(length 3.81)
					(name "153"
						(effects
							(font
								(size 1.27 1.27)
							)
						)
					)
					(number "153"
						(effects
							(font
								(size 1.27 1.27)
							)
						)
					)
				)
				(pin passive line
					(at 0 -30.48 0)
					(length 3.81)
					(name "155"
						(effects
							(font
								(size 1.27 1.27)
							)
						)
					)
					(number "155"
						(effects
							(font
								(size 1.27 1.27)
							)
						)
					)
				)
				(pin passive line
					(at 0 -33.02 0)
					(length 3.81)
					(name "157"
						(effects
							(font
								(size 1.27 1.27)
							)
						)
					)
					(number "157"
						(effects
							(font
								(size 1.27 1.27)
							)
						)
					)
				)
				(pin passive line
					(at 0 -35.56 0)
					(length 3.81)
					(name "159"
						(effects
							(font
								(size 1.27 1.27)
							)
						)
					)
					(number "159"
						(effects
							(font
								(size 1.27 1.27)
							)
						)
					)
				)
				(pin passive line
					(at 0 -38.1 0)
					(length 3.81)
					(name "161"
						(effects
							(font
								(size 1.27 1.27)
							)
						)
					)
					(number "161"
						(effects
							(font
								(size 1.27 1.27)
							)
						)
					)
				)
				(pin passive line
					(at 0 -40.64 0)
					(length 3.81)
					(name "163"
						(effects
							(font
								(size 1.27 1.27)
							)
						)
					)
					(number "163"
						(effects
							(font
								(size 1.27 1.27)
							)
						)
					)
				)
				(pin passive line
					(at 0 -43.18 0)
					(length 3.81)
					(name "165"
						(effects
							(font
								(size 1.27 1.27)
							)
						)
					)
					(number "165"
						(effects
							(font
								(size 1.27 1.27)
							)
						)
					)
				)
				(pin passive line
					(at 0 -45.72 0)
					(length 3.81)
					(name "167"
						(effects
							(font
								(size 1.27 1.27)
							)
						)
					)
					(number "167"
						(effects
							(font
								(size 1.27 1.27)
							)
						)
					)
				)
				(pin passive line
					(at 0 -48.26 0)
					(length 3.81)
					(name "169"
						(effects
							(font
								(size 1.27 1.27)
							)
						)
					)
					(number "169"
						(effects
							(font
								(size 1.27 1.27)
							)
						)
					)
				)
				(pin passive line
					(at 0 -50.8 0)
					(length 3.81)
					(name "171"
						(effects
							(font
								(size 1.27 1.27)
							)
						)
					)
					(number "171"
						(effects
							(font
								(size 1.27 1.27)
							)
						)
					)
				)
				(pin passive line
					(at 0 -53.34 0)
					(length 3.81)
					(name "173"
						(effects
							(font
								(size 1.27 1.27)
							)
						)
					)
					(number "173"
						(effects
							(font
								(size 1.27 1.27)
							)
						)
					)
				)
				(pin passive line
					(at 0 -55.88 0)
					(length 3.81)
					(name "175"
						(effects
							(font
								(size 1.27 1.27)
							)
						)
					)
					(number "175"
						(effects
							(font
								(size 1.27 1.27)
							)
						)
					)
				)
				(pin passive line
					(at 0 -58.42 0)
					(length 3.81)
					(name "177"
						(effects
							(font
								(size 1.27 1.27)
							)
						)
					)
					(number "177"
						(effects
							(font
								(size 1.27 1.27)
							)
						)
					)
				)
				(pin passive line
					(at 0 -60.96 0)
					(length 3.81)
					(name "179"
						(effects
							(font
								(size 1.27 1.27)
							)
						)
					)
					(number "179"
						(effects
							(font
								(size 1.27 1.27)
							)
						)
					)
				)
				(pin passive line
					(at 0 -63.5 0)
					(length 3.81)
					(name "181"
						(effects
							(font
								(size 1.27 1.27)
							)
						)
					)
					(number "181"
						(effects
							(font
								(size 1.27 1.27)
							)
						)
					)
				)
				(pin passive line
					(at 0 -66.04 0)
					(length 3.81)
					(name "183"
						(effects
							(font
								(size 1.27 1.27)
							)
						)
					)
					(number "183"
						(effects
							(font
								(size 1.27 1.27)
							)
						)
					)
				)
				(pin passive line
					(at 0 -68.58 0)
					(length 3.81)
					(name "185"
						(effects
							(font
								(size 1.27 1.27)
							)
						)
					)
					(number "185"
						(effects
							(font
								(size 1.27 1.27)
							)
						)
					)
				)
				(pin passive line
					(at 0 -71.12 0)
					(length 3.81)
					(name "187"
						(effects
							(font
								(size 1.27 1.27)
							)
						)
					)
					(number "187"
						(effects
							(font
								(size 1.27 1.27)
							)
						)
					)
				)
				(pin passive line
					(at 0 -73.66 0)
					(length 3.81)
					(name "189"
						(effects
							(font
								(size 1.27 1.27)
							)
						)
					)
					(number "189"
						(effects
							(font
								(size 1.27 1.27)
							)
						)
					)
				)
				(pin passive line
					(at 0 -76.2 0)
					(length 3.81)
					(name "191"
						(effects
							(font
								(size 1.27 1.27)
							)
						)
					)
					(number "191"
						(effects
							(font
								(size 1.27 1.27)
							)
						)
					)
				)
				(pin passive line
					(at 0 -78.74 0)
					(length 3.81)
					(name "193"
						(effects
							(font
								(size 1.27 1.27)
							)
						)
					)
					(number "193"
						(effects
							(font
								(size 1.27 1.27)
							)
						)
					)
				)
				(pin passive line
					(at 0 -81.28 0)
					(length 3.81)
					(name "195"
						(effects
							(font
								(size 1.27 1.27)
							)
						)
					)
					(number "195"
						(effects
							(font
								(size 1.27 1.27)
							)
						)
					)
				)
				(pin passive line
					(at 0 -83.82 0)
					(length 3.81)
					(name "197"
						(effects
							(font
								(size 1.27 1.27)
							)
						)
					)
					(number "197"
						(effects
							(font
								(size 1.27 1.27)
							)
						)
					)
				)
				(pin passive line
					(at 0 -86.36 0)
					(length 3.81)
					(name "199"
						(effects
							(font
								(size 1.27 1.27)
							)
						)
					)
					(number "199"
						(effects
							(font
								(size 1.27 1.27)
							)
						)
					)
				)
				(pin passive line
					(at 0 -88.9 0)
					(length 3.81)
					(name "201"
						(effects
							(font
								(size 1.27 1.27)
							)
						)
					)
					(number "201"
						(effects
							(font
								(size 1.27 1.27)
							)
						)
					)
				)
				(pin passive line
					(at 0 -91.44 0)
					(length 3.81)
					(name "203"
						(effects
							(font
								(size 1.27 1.27)
							)
						)
					)
					(number "203"
						(effects
							(font
								(size 1.27 1.27)
							)
						)
					)
				)
				(pin passive line
					(at 0 -93.98 0)
					(length 3.81)
					(name "205"
						(effects
							(font
								(size 1.27 1.27)
							)
						)
					)
					(number "205"
						(effects
							(font
								(size 1.27 1.27)
							)
						)
					)
				)
				(pin passive line
					(at 0 -96.52 0)
					(length 3.81)
					(name "207"
						(effects
							(font
								(size 1.27 1.27)
							)
						)
					)
					(number "207"
						(effects
							(font
								(size 1.27 1.27)
							)
						)
					)
				)
				(pin passive line
					(at 0 -99.06 0)
					(length 3.81)
					(name "209"
						(effects
							(font
								(size 1.27 1.27)
							)
						)
					)
					(number "209"
						(effects
							(font
								(size 1.27 1.27)
							)
						)
					)
				)
				(pin passive line
					(at 0 -101.6 0)
					(length 3.81)
					(name "211"
						(effects
							(font
								(size 1.27 1.27)
							)
						)
					)
					(number "211"
						(effects
							(font
								(size 1.27 1.27)
							)
						)
					)
				)
				(pin passive line
					(at 0 -104.14 0)
					(length 3.81)
					(name "213"
						(effects
							(font
								(size 1.27 1.27)
							)
						)
					)
					(number "213"
						(effects
							(font
								(size 1.27 1.27)
							)
						)
					)
				)
				(pin passive line
					(at 0 -106.68 0)
					(length 3.81)
					(name "215"
						(effects
							(font
								(size 1.27 1.27)
							)
						)
					)
					(number "215"
						(effects
							(font
								(size 1.27 1.27)
							)
						)
					)
				)
				(pin passive line
					(at 0 -109.22 0)
					(length 3.81)
					(name "217"
						(effects
							(font
								(size 1.27 1.27)
							)
						)
					)
					(number "217"
						(effects
							(font
								(size 1.27 1.27)
							)
						)
					)
				)
				(pin passive line
					(at 0 -111.76 0)
					(length 3.81)
					(name "219"
						(effects
							(font
								(size 1.27 1.27)
							)
						)
					)
					(number "219"
						(effects
							(font
								(size 1.27 1.27)
							)
						)
					)
				)
				(pin passive line
					(at 0 -114.3 0)
					(length 3.81)
					(name "221"
						(effects
							(font
								(size 1.27 1.27)
							)
						)
					)
					(number "221"
						(effects
							(font
								(size 1.27 1.27)
							)
						)
					)
				)
				(pin passive line
					(at 0 -116.84 0)
					(length 3.81)
					(name "223"
						(effects
							(font
								(size 1.27 1.27)
							)
						)
					)
					(number "223"
						(effects
							(font
								(size 1.27 1.27)
							)
						)
					)
				)
				(pin passive line
					(at 0 -119.38 0)
					(length 3.81)
					(name "225"
						(effects
							(font
								(size 1.27 1.27)
							)
						)
					)
					(number "225"
						(effects
							(font
								(size 1.27 1.27)
							)
						)
					)
				)
				(pin passive line
					(at 0 -121.92 0)
					(length 3.81)
					(name "227"
						(effects
							(font
								(size 1.27 1.27)
							)
						)
					)
					(number "227"
						(effects
							(font
								(size 1.27 1.27)
							)
						)
					)
				)
				(pin passive line
					(at 0 -124.46 0)
					(length 3.81)
					(name "229"
						(effects
							(font
								(size 1.27 1.27)
							)
						)
					)
					(number "229"
						(effects
							(font
								(size 1.27 1.27)
							)
						)
					)
				)
				(pin passive line
					(at 0 -127 0)
					(length 3.81)
					(name "231"
						(effects
							(font
								(size 1.27 1.27)
							)
						)
					)
					(number "231"
						(effects
							(font
								(size 1.27 1.27)
							)
						)
					)
				)
				(pin passive line
					(at 0 -129.54 0)
					(length 3.81)
					(name "233"
						(effects
							(font
								(size 1.27 1.27)
							)
						)
					)
					(number "233"
						(effects
							(font
								(size 1.27 1.27)
							)
						)
					)
				)
				(pin passive line
					(at 0 -132.08 0)
					(length 3.81)
					(name "235"
						(effects
							(font
								(size 1.27 1.27)
							)
						)
					)
					(number "235"
						(effects
							(font
								(size 1.27 1.27)
							)
						)
					)
				)
				(pin passive line
					(at 0 -134.62 0)
					(length 3.81)
					(name "237"
						(effects
							(font
								(size 1.27 1.27)
							)
						)
					)
					(number "237"
						(effects
							(font
								(size 1.27 1.27)
							)
						)
					)
				)
				(pin passive line
					(at 0 -137.16 0)
					(length 3.81)
					(name "239"
						(effects
							(font
								(size 1.27 1.27)
							)
						)
					)
					(number "239"
						(effects
							(font
								(size 1.27 1.27)
							)
						)
					)
				)
				(pin passive line
					(at 0 -139.7 0)
					(length 3.81)
					(name "241"
						(effects
							(font
								(size 1.27 1.27)
							)
						)
					)
					(number "241"
						(effects
							(font
								(size 1.27 1.27)
							)
						)
					)
				)
				(pin passive line
					(at 0 -142.24 0)
					(length 3.81)
					(name "243"
						(effects
							(font
								(size 1.27 1.27)
							)
						)
					)
					(number "243"
						(effects
							(font
								(size 1.27 1.27)
							)
						)
					)
				)
				(pin passive line
					(at 0 -144.78 0)
					(length 3.81)
					(name "245"
						(effects
							(font
								(size 1.27 1.27)
							)
						)
					)
					(number "245"
						(effects
							(font
								(size 1.27 1.27)
							)
						)
					)
				)
				(pin passive line
					(at 0 -147.32 0)
					(length 3.81)
					(name "247"
						(effects
							(font
								(size 1.27 1.27)
							)
						)
					)
					(number "247"
						(effects
							(font
								(size 1.27 1.27)
							)
						)
					)
				)
				(pin passive line
					(at 0 -149.86 0)
					(length 3.81)
					(name "249"
						(effects
							(font
								(size 1.27 1.27)
							)
						)
					)
					(number "249"
						(effects
							(font
								(size 1.27 1.27)
							)
						)
					)
				)
				(pin passive line
					(at 0 -152.4 0)
					(length 3.81)
					(name "251"
						(effects
							(font
								(size 1.27 1.27)
							)
						)
					)
					(number "251"
						(effects
							(font
								(size 1.27 1.27)
							)
						)
					)
				)
				(pin passive line
					(at 0 -154.94 0)
					(length 3.81)
					(name "253"
						(effects
							(font
								(size 1.27 1.27)
							)
						)
					)
					(number "253"
						(effects
							(font
								(size 1.27 1.27)
							)
						)
					)
				)
				(pin passive line
					(at 0 -157.48 0)
					(length 3.81)
					(name "255"
						(effects
							(font
								(size 1.27 1.27)
							)
						)
					)
					(number "255"
						(effects
							(font
								(size 1.27 1.27)
							)
						)
					)
				)
				(pin passive line
					(at 0 -160.02 0)
					(length 3.81)
					(name "257"
						(effects
							(font
								(size 1.27 1.27)
							)
						)
					)
					(number "257"
						(effects
							(font
								(size 1.27 1.27)
							)
						)
					)
				)
				(pin passive line
					(at 0 -162.56 0)
					(length 3.81)
					(name "259"
						(effects
							(font
								(size 1.27 1.27)
							)
						)
					)
					(number "259"
						(effects
							(font
								(size 1.27 1.27)
							)
						)
					)
				)
				(pin passive line
					(at 22.86 0 180)
					(length 3.81)
					(name "132"
						(effects
							(font
								(size 1.27 1.27)
							)
						)
					)
					(number "132"
						(effects
							(font
								(size 1.27 1.27)
							)
						)
					)
				)
				(pin passive line
					(at 22.86 -2.54 180)
					(length 3.81)
					(name "134"
						(effects
							(font
								(size 1.27 1.27)
							)
						)
					)
					(number "134"
						(effects
							(font
								(size 1.27 1.27)
							)
						)
					)
				)
				(pin passive line
					(at 22.86 -5.08 180)
					(length 3.81)
					(name "136"
						(effects
							(font
								(size 1.27 1.27)
							)
						)
					)
					(number "136"
						(effects
							(font
								(size 1.27 1.27)
							)
						)
					)
				)
				(pin passive line
					(at 22.86 -7.62 180)
					(length 3.81)
					(name "138"
						(effects
							(font
								(size 1.27 1.27)
							)
						)
					)
					(number "138"
						(effects
							(font
								(size 1.27 1.27)
							)
						)
					)
				)
				(pin passive line
					(at 22.86 -10.16 180)
					(length 3.81)
					(name "140"
						(effects
							(font
								(size 1.27 1.27)
							)
						)
					)
					(number "140"
						(effects
							(font
								(size 1.27 1.27)
							)
						)
					)
				)
				(pin passive line
					(at 22.86 -12.7 180)
					(length 3.81)
					(name "142"
						(effects
							(font
								(size 1.27 1.27)
							)
						)
					)
					(number "142"
						(effects
							(font
								(size 1.27 1.27)
							)
						)
					)
				)
				(pin passive line
					(at 22.86 -15.24 180)
					(length 3.81)
					(name "144"
						(effects
							(font
								(size 1.27 1.27)
							)
						)
					)
					(number "144"
						(effects
							(font
								(size 1.27 1.27)
							)
						)
					)
				)
				(pin passive line
					(at 22.86 -17.78 180)
					(length 3.81)
					(name "146"
						(effects
							(font
								(size 1.27 1.27)
							)
						)
					)
					(number "146"
						(effects
							(font
								(size 1.27 1.27)
							)
						)
					)
				)
				(pin passive line
					(at 22.86 -20.32 180)
					(length 3.81)
					(name "148"
						(effects
							(font
								(size 1.27 1.27)
							)
						)
					)
					(number "148"
						(effects
							(font
								(size 1.27 1.27)
							)
						)
					)
				)
				(pin passive line
					(at 22.86 -22.86 180)
					(length 3.81)
					(name "150"
						(effects
							(font
								(size 1.27 1.27)
							)
						)
					)
					(number "150"
						(effects
							(font
								(size 1.27 1.27)
							)
						)
					)
				)
				(pin passive line
					(at 22.86 -25.4 180)
					(length 3.81)
					(name "152"
						(effects
							(font
								(size 1.27 1.27)
							)
						)
					)
					(number "152"
						(effects
							(font
								(size 1.27 1.27)
							)
						)
					)
				)
				(pin passive line
					(at 22.86 -27.94 180)
					(length 3.81)
					(name "154"
						(effects
							(font
								(size 1.27 1.27)
							)
						)
					)
					(number "154"
						(effects
							(font
								(size 1.27 1.27)
							)
						)
					)
				)
				(pin passive line
					(at 22.86 -30.48 180)
					(length 3.81)
					(name "156"
						(effects
							(font
								(size 1.27 1.27)
							)
						)
					)
					(number "156"
						(effects
							(font
								(size 1.27 1.27)
							)
						)
					)
				)
				(pin passive line
					(at 22.86 -33.02 180)
					(length 3.81)
					(name "158"
						(effects
							(font
								(size 1.27 1.27)
							)
						)
					)
					(number "158"
						(effects
							(font
								(size 1.27 1.27)
							)
						)
					)
				)
				(pin passive line
					(at 22.86 -35.56 180)
					(length 3.81)
					(name "160"
						(effects
							(font
								(size 1.27 1.27)
							)
						)
					)
					(number "160"
						(effects
							(font
								(size 1.27 1.27)
							)
						)
					)
				)
				(pin passive line
					(at 22.86 -38.1 180)
					(length 3.81)
					(name "162"
						(effects
							(font
								(size 1.27 1.27)
							)
						)
					)
					(number "162"
						(effects
							(font
								(size 1.27 1.27)
							)
						)
					)
				)
				(pin passive line
					(at 22.86 -40.64 180)
					(length 3.81)
					(name "164"
						(effects
							(font
								(size 1.27 1.27)
							)
						)
					)
					(number "164"
						(effects
							(font
								(size 1.27 1.27)
							)
						)
					)
				)
				(pin passive line
					(at 22.86 -43.18 180)
					(length 3.81)
					(name "166"
						(effects
							(font
								(size 1.27 1.27)
							)
						)
					)
					(number "166"
						(effects
							(font
								(size 1.27 1.27)
							)
						)
					)
				)
				(pin passive line
					(at 22.86 -45.72 180)
					(length 3.81)
					(name "168"
						(effects
							(font
								(size 1.27 1.27)
							)
						)
					)
					(number "168"
						(effects
							(font
								(size 1.27 1.27)
							)
						)
					)
				)
				(pin passive line
					(at 22.86 -48.26 180)
					(length 3.81)
					(name "170"
						(effects
							(font
								(size 1.27 1.27)
							)
						)
					)
					(number "170"
						(effects
							(font
								(size 1.27 1.27)
							)
						)
					)
				)
				(pin passive line
					(at 22.86 -50.8 180)
					(length 3.81)
					(name "172"
						(effects
							(font
								(size 1.27 1.27)
							)
						)
					)
					(number "172"
						(effects
							(font
								(size 1.27 1.27)
							)
						)
					)
				)
				(pin passive line
					(at 22.86 -53.34 180)
					(length 3.81)
					(name "174"
						(effects
							(font
								(size 1.27 1.27)
							)
						)
					)
					(number "174"
						(effects
							(font
								(size 1.27 1.27)
							)
						)
					)
				)
				(pin passive line
					(at 22.86 -55.88 180)
					(length 3.81)
					(name "176"
						(effects
							(font
								(size 1.27 1.27)
							)
						)
					)
					(number "176"
						(effects
							(font
								(size 1.27 1.27)
							)
						)
					)
				)
				(pin passive line
					(at 22.86 -58.42 180)
					(length 3.81)
					(name "178"
						(effects
							(font
								(size 1.27 1.27)
							)
						)
					)
					(number "178"
						(effects
							(font
								(size 1.27 1.27)
							)
						)
					)
				)
				(pin passive line
					(at 22.86 -60.96 180)
					(length 3.81)
					(name "180"
						(effects
							(font
								(size 1.27 1.27)
							)
						)
					)
					(number "180"
						(effects
							(font
								(size 1.27 1.27)
							)
						)
					)
				)
				(pin passive line
					(at 22.86 -63.5 180)
					(length 3.81)
					(name "182"
						(effects
							(font
								(size 1.27 1.27)
							)
						)
					)
					(number "182"
						(effects
							(font
								(size 1.27 1.27)
							)
						)
					)
				)
				(pin passive line
					(at 22.86 -66.04 180)
					(length 3.81)
					(name "184"
						(effects
							(font
								(size 1.27 1.27)
							)
						)
					)
					(number "184"
						(effects
							(font
								(size 1.27 1.27)
							)
						)
					)
				)
				(pin passive line
					(at 22.86 -68.58 180)
					(length 3.81)
					(name "186"
						(effects
							(font
								(size 1.27 1.27)
							)
						)
					)
					(number "186"
						(effects
							(font
								(size 1.27 1.27)
							)
						)
					)
				)
				(pin passive line
					(at 22.86 -71.12 180)
					(length 3.81)
					(name "188"
						(effects
							(font
								(size 1.27 1.27)
							)
						)
					)
					(number "188"
						(effects
							(font
								(size 1.27 1.27)
							)
						)
					)
				)
				(pin passive line
					(at 22.86 -73.66 180)
					(length 3.81)
					(name "190"
						(effects
							(font
								(size 1.27 1.27)
							)
						)
					)
					(number "190"
						(effects
							(font
								(size 1.27 1.27)
							)
						)
					)
				)
				(pin passive line
					(at 22.86 -76.2 180)
					(length 3.81)
					(name "192"
						(effects
							(font
								(size 1.27 1.27)
							)
						)
					)
					(number "192"
						(effects
							(font
								(size 1.27 1.27)
							)
						)
					)
				)
				(pin passive line
					(at 22.86 -78.74 180)
					(length 3.81)
					(name "194"
						(effects
							(font
								(size 1.27 1.27)
							)
						)
					)
					(number "194"
						(effects
							(font
								(size 1.27 1.27)
							)
						)
					)
				)
				(pin passive line
					(at 22.86 -81.28 180)
					(length 3.81)
					(name "196"
						(effects
							(font
								(size 1.27 1.27)
							)
						)
					)
					(number "196"
						(effects
							(font
								(size 1.27 1.27)
							)
						)
					)
				)
				(pin passive line
					(at 22.86 -83.82 180)
					(length 3.81)
					(name "198"
						(effects
							(font
								(size 1.27 1.27)
							)
						)
					)
					(number "198"
						(effects
							(font
								(size 1.27 1.27)
							)
						)
					)
				)
				(pin passive line
					(at 22.86 -86.36 180)
					(length 3.81)
					(name "200"
						(effects
							(font
								(size 1.27 1.27)
							)
						)
					)
					(number "200"
						(effects
							(font
								(size 1.27 1.27)
							)
						)
					)
				)
				(pin passive line
					(at 22.86 -88.9 180)
					(length 3.81)
					(name "202"
						(effects
							(font
								(size 1.27 1.27)
							)
						)
					)
					(number "202"
						(effects
							(font
								(size 1.27 1.27)
							)
						)
					)
				)
				(pin passive line
					(at 22.86 -91.44 180)
					(length 3.81)
					(name "204"
						(effects
							(font
								(size 1.27 1.27)
							)
						)
					)
					(number "204"
						(effects
							(font
								(size 1.27 1.27)
							)
						)
					)
				)
				(pin passive line
					(at 22.86 -93.98 180)
					(length 3.81)
					(name "206"
						(effects
							(font
								(size 1.27 1.27)
							)
						)
					)
					(number "206"
						(effects
							(font
								(size 1.27 1.27)
							)
						)
					)
				)
				(pin passive line
					(at 22.86 -96.52 180)
					(length 3.81)
					(name "208"
						(effects
							(font
								(size 1.27 1.27)
							)
						)
					)
					(number "208"
						(effects
							(font
								(size 1.27 1.27)
							)
						)
					)
				)
				(pin passive line
					(at 22.86 -99.06 180)
					(length 3.81)
					(name "210"
						(effects
							(font
								(size 1.27 1.27)
							)
						)
					)
					(number "210"
						(effects
							(font
								(size 1.27 1.27)
							)
						)
					)
				)
				(pin passive line
					(at 22.86 -101.6 180)
					(length 3.81)
					(name "212"
						(effects
							(font
								(size 1.27 1.27)
							)
						)
					)
					(number "212"
						(effects
							(font
								(size 1.27 1.27)
							)
						)
					)
				)
				(pin passive line
					(at 22.86 -104.14 180)
					(length 3.81)
					(name "214"
						(effects
							(font
								(size 1.27 1.27)
							)
						)
					)
					(number "214"
						(effects
							(font
								(size 1.27 1.27)
							)
						)
					)
				)
				(pin passive line
					(at 22.86 -106.68 180)
					(length 3.81)
					(name "216"
						(effects
							(font
								(size 1.27 1.27)
							)
						)
					)
					(number "216"
						(effects
							(font
								(size 1.27 1.27)
							)
						)
					)
				)
				(pin passive line
					(at 22.86 -109.22 180)
					(length 3.81)
					(name "218"
						(effects
							(font
								(size 1.27 1.27)
							)
						)
					)
					(number "218"
						(effects
							(font
								(size 1.27 1.27)
							)
						)
					)
				)
				(pin passive line
					(at 22.86 -111.76 180)
					(length 3.81)
					(name "220"
						(effects
							(font
								(size 1.27 1.27)
							)
						)
					)
					(number "220"
						(effects
							(font
								(size 1.27 1.27)
							)
						)
					)
				)
				(pin passive line
					(at 22.86 -114.3 180)
					(length 3.81)
					(name "222"
						(effects
							(font
								(size 1.27 1.27)
							)
						)
					)
					(number "222"
						(effects
							(font
								(size 1.27 1.27)
							)
						)
					)
				)
				(pin passive line
					(at 22.86 -116.84 180)
					(length 3.81)
					(name "224"
						(effects
							(font
								(size 1.27 1.27)
							)
						)
					)
					(number "224"
						(effects
							(font
								(size 1.27 1.27)
							)
						)
					)
				)
				(pin passive line
					(at 22.86 -119.38 180)
					(length 3.81)
					(name "226"
						(effects
							(font
								(size 1.27 1.27)
							)
						)
					)
					(number "226"
						(effects
							(font
								(size 1.27 1.27)
							)
						)
					)
				)
				(pin passive line
					(at 22.86 -121.92 180)
					(length 3.81)
					(name "228"
						(effects
							(font
								(size 1.27 1.27)
							)
						)
					)
					(number "228"
						(effects
							(font
								(size 1.27 1.27)
							)
						)
					)
				)
				(pin passive line
					(at 22.86 -124.46 180)
					(length 3.81)
					(name "230"
						(effects
							(font
								(size 1.27 1.27)
							)
						)
					)
					(number "230"
						(effects
							(font
								(size 1.27 1.27)
							)
						)
					)
				)
				(pin passive line
					(at 22.86 -127 180)
					(length 3.81)
					(name "232"
						(effects
							(font
								(size 1.27 1.27)
							)
						)
					)
					(number "232"
						(effects
							(font
								(size 1.27 1.27)
							)
						)
					)
				)
				(pin passive line
					(at 22.86 -129.54 180)
					(length 3.81)
					(name "234"
						(effects
							(font
								(size 1.27 1.27)
							)
						)
					)
					(number "234"
						(effects
							(font
								(size 1.27 1.27)
							)
						)
					)
				)
				(pin passive line
					(at 22.86 -132.08 180)
					(length 3.81)
					(name "236"
						(effects
							(font
								(size 1.27 1.27)
							)
						)
					)
					(number "236"
						(effects
							(font
								(size 1.27 1.27)
							)
						)
					)
				)
				(pin passive line
					(at 22.86 -134.62 180)
					(length 3.81)
					(name "238"
						(effects
							(font
								(size 1.27 1.27)
							)
						)
					)
					(number "238"
						(effects
							(font
								(size 1.27 1.27)
							)
						)
					)
				)
				(pin passive line
					(at 22.86 -137.16 180)
					(length 3.81)
					(name "240"
						(effects
							(font
								(size 1.27 1.27)
							)
						)
					)
					(number "240"
						(effects
							(font
								(size 1.27 1.27)
							)
						)
					)
				)
				(pin passive line
					(at 22.86 -139.7 180)
					(length 3.81)
					(name "242"
						(effects
							(font
								(size 1.27 1.27)
							)
						)
					)
					(number "242"
						(effects
							(font
								(size 1.27 1.27)
							)
						)
					)
				)
				(pin passive line
					(at 22.86 -142.24 180)
					(length 3.81)
					(name "244"
						(effects
							(font
								(size 1.27 1.27)
							)
						)
					)
					(number "244"
						(effects
							(font
								(size 1.27 1.27)
							)
						)
					)
				)
				(pin passive line
					(at 22.86 -144.78 180)
					(length 3.81)
					(name "246"
						(effects
							(font
								(size 1.27 1.27)
							)
						)
					)
					(number "246"
						(effects
							(font
								(size 1.27 1.27)
							)
						)
					)
				)
				(pin passive line
					(at 22.86 -147.32 180)
					(length 3.81)
					(name "248"
						(effects
							(font
								(size 1.27 1.27)
							)
						)
					)
					(number "248"
						(effects
							(font
								(size 1.27 1.27)
							)
						)
					)
				)
				(pin passive line
					(at 22.86 -149.86 180)
					(length 3.81)
					(name "250"
						(effects
							(font
								(size 1.27 1.27)
							)
						)
					)
					(number "250"
						(effects
							(font
								(size 1.27 1.27)
							)
						)
					)
				)
				(pin passive line
					(at 22.86 -152.4 180)
					(length 3.81)
					(name "252"
						(effects
							(font
								(size 1.27 1.27)
							)
						)
					)
					(number "252"
						(effects
							(font
								(size 1.27 1.27)
							)
						)
					)
				)
				(pin passive line
					(at 22.86 -154.94 180)
					(length 3.81)
					(name "254"
						(effects
							(font
								(size 1.27 1.27)
							)
						)
					)
					(number "254"
						(effects
							(font
								(size 1.27 1.27)
							)
						)
					)
				)
				(pin passive line
					(at 22.86 -157.48 180)
					(length 3.81)
					(name "256"
						(effects
							(font
								(size 1.27 1.27)
							)
						)
					)
					(number "256"
						(effects
							(font
								(size 1.27 1.27)
							)
						)
					)
				)
				(pin passive line
					(at 22.86 -160.02 180)
					(length 3.81)
					(name "258"
						(effects
							(font
								(size 1.27 1.27)
							)
						)
					)
					(number "258"
						(effects
							(font
								(size 1.27 1.27)
							)
						)
					)
				)
				(pin passive line
					(at 22.86 -162.56 180)
					(length 3.81)
					(name "260"
						(effects
							(font
								(size 1.27 1.27)
							)
						)
					)
					(number "260"
						(effects
							(font
								(size 1.27 1.27)
							)
						)
					)
				)
			)
		)
	(symbol "antmicroMemoryConnectorsPCCardSockets:MicroSD_1140084168"
			(exclude_from_sim no)
			(in_bom yes)
			(on_board yes)
			(property "Reference" "J"
				(at 38.1 -3.81 0)
				(effects
					(font
						(size 1.27 1.27)
						(thickness 0.15)
					)
					(justify left bottom)
				)
			)
			(property "Value" "MicroSD_1140084168"
				(at 38.1 -6.35 0)
				(effects
					(font
						(size 1.27 1.27)
						(thickness 0.15)
					)
					(justify left bottom)
				)
			)
			(property "Footprint" "antmicro-footprints:MicroSD_Amphenol_1140084168"
				(at 38.1 -8.89 0)
				(effects
					(font
						(size 1.27 1.27)
						(thickness 0.15)
					)
					(justify left bottom)
					(hide yes)
				)
			)
			(property "Datasheet" "https://cdn.amphenol-cs.com/media/wysiwyg/files/documentation/datasheet/inputoutput/io_micro_sdcard.pdf"
				(at 38.1 -11.43 0)
				(effects
					(font
						(size 1.27 1.27)
						(thickness 0.15)
					)
					(justify left bottom)
					(hide yes)
				)
			)
			(property "Description" "Micro SD Right Angle, PCB Mount"
				(at 0 0 0)
				(effects
					(font
						(size 1.27 1.27)
					)
					(hide yes)
				)
			)
			(property "MPN" "1140084168"
				(at 38.1 -13.97 0)
				(effects
					(font
						(size 1.27 1.27)
						(thickness 0.15)
					)
					(justify left bottom)
					(hide yes)
				)
			)
			(property "Manufacturer" "Amphenol"
				(at 38.1 -16.51 0)
				(effects
					(font
						(size 1.27 1.27)
						(thickness 0.15)
					)
					(justify left bottom)
					(hide yes)
				)
			)
			(property "Author" "Antmicro"
				(at 38.1 -19.05 0)
				(effects
					(font
						(size 1.27 1.27)
						(thickness 0.15)
					)
					(justify left bottom)
					(hide yes)
				)
			)
			(property "License" "Apache-2.0"
				(at 38.1 -21.59 0)
				(effects
					(font
						(size 1.27 1.27)
						(thickness 0.15)
					)
					(justify left bottom)
					(hide yes)
				)
			)
			(symbol "MicroSD_1140084168_1_1"
				(polyline
					(pts
						(xy 2.54 2.54) (xy 2.54 -24.13) (xy 10.16 -24.13) (xy 13.97 -24.13) (xy 19.05 -24.13) (xy 19.05 -16.51)
						(xy 24.13 -11.43) (xy 24.13 2.54) (xy 2.54 2.54)
					)
					(stroke
						(width 0.254)
						(type default)
					)
					(fill
						(type background)
					)
				)
				(text "microSD CARD"
					(at 19.05 -12.7 900)
					(effects
						(font
							(size 1.27 1.27)
							(thickness 0.15)
						)
						(justify left bottom)
					)
				)
				(pin bidirectional line
					(at 0 0 0)
					(length 2.54)
					(name "DAT2"
						(effects
							(font
								(size 1.27 1.27)
							)
						)
					)
					(number "1"
						(effects
							(font
								(size 1.27 1.27)
							)
						)
					)
				)
				(pin bidirectional line
					(at 0 -2.54 0)
					(length 2.54)
					(name "CD/DAT3"
						(effects
							(font
								(size 1.27 1.27)
							)
						)
					)
					(number "2"
						(effects
							(font
								(size 1.27 1.27)
							)
						)
					)
				)
				(pin bidirectional line
					(at 0 -5.08 0)
					(length 2.54)
					(name "CMD"
						(effects
							(font
								(size 1.27 1.27)
							)
						)
					)
					(number "3"
						(effects
							(font
								(size 1.27 1.27)
							)
						)
					)
				)
				(pin power_in line
					(at 0 -7.62 0)
					(length 2.54)
					(name "VDD"
						(effects
							(font
								(size 1.27 1.27)
							)
						)
					)
					(number "4"
						(effects
							(font
								(size 1.27 1.27)
							)
						)
					)
				)
				(pin output line
					(at 0 -10.16 0)
					(length 2.54)
					(name "CLK"
						(effects
							(font
								(size 1.27 1.27)
							)
						)
					)
					(number "5"
						(effects
							(font
								(size 1.27 1.27)
							)
						)
					)
				)
				(pin power_in line
					(at 0 -12.7 0)
					(length 2.54)
					(name "VSS"
						(effects
							(font
								(size 1.27 1.27)
							)
						)
					)
					(number "6"
						(effects
							(font
								(size 1.27 1.27)
							)
						)
					)
				)
				(pin bidirectional line
					(at 0 -15.24 0)
					(length 2.54)
					(name "DAT0"
						(effects
							(font
								(size 1.27 1.27)
							)
						)
					)
					(number "7"
						(effects
							(font
								(size 1.27 1.27)
							)
						)
					)
				)
				(pin bidirectional line
					(at 0 -17.78 0)
					(length 2.54)
					(name "DAT1"
						(effects
							(font
								(size 1.27 1.27)
							)
						)
					)
					(number "8"
						(effects
							(font
								(size 1.27 1.27)
							)
						)
					)
				)
				(pin passive line
					(at 0 -20.32 0)
					(length 2.54)
					(name "CD1"
						(effects
							(font
								(size 1.27 1.27)
							)
						)
					)
					(number "9"
						(effects
							(font
								(size 1.27 1.27)
							)
						)
					)
				)
				(pin passive line
					(at 0 -22.86 0)
					(length 2.54)
					(name "CD2"
						(effects
							(font
								(size 1.27 1.27)
							)
						)
					)
					(number "10"
						(effects
							(font
								(size 1.27 1.27)
							)
						)
					)
				)
				(pin passive line
					(at 21.59 -20.32 180)
					(length 2.54)
					(name "Shell"
						(effects
							(font
								(size 1.27 1.27)
							)
						)
					)
					(number "SH"
						(effects
							(font
								(size 1.27 1.27)
							)
						)
					)
				)
			)
		)
	(symbol "antmicroModularConnectorsJacksWithMagnetics:Bus_RJ45_7499111121A"
			(exclude_from_sim no)
			(in_bom yes)
			(on_board yes)
			(property "Reference" "J"
				(at 41.91 0 0)
				(effects
					(font
						(size 1.27 1.27)
						(thickness 0.15)
					)
					(justify left bottom)
				)
			)
			(property "Value" "Bus_RJ45_7499111121A"
				(at 41.91 -2.54 0)
				(effects
					(font
						(size 1.27 1.27)
						(thickness 0.15)
					)
					(justify left bottom)
				)
			)
			(property "Footprint" "antmicro-footprints:RJ45_7499111121A_Horizontal"
				(at 41.91 -5.08 0)
				(effects
					(font
						(size 1.27 1.27)
						(thickness 0.15)
					)
					(justify left bottom)
					(hide yes)
				)
			)
			(property "Datasheet" "https://www.we-online.com/components/products/datasheet/7499111121A.pdf"
				(at 41.91 -7.62 0)
				(effects
					(font
						(size 1.27 1.27)
						(thickness 0.15)
					)
					(justify left bottom)
					(hide yes)
				)
			)
			(property "Description" ""
				(at 0 0 0)
				(effects
					(font
						(size 1.27 1.27)
					)
					(hide yes)
				)
			)
			(property "MPN" "7499111121A"
				(at 41.91 -10.16 0)
				(effects
					(font
						(size 1.27 1.27)
						(thickness 0.15)
					)
					(justify left bottom)
					(hide yes)
				)
			)
			(property "Manufacturer" "Würth Elektronik"
				(at 41.91 -12.7 0)
				(effects
					(font
						(size 1.27 1.27)
						(thickness 0.15)
					)
					(justify left bottom)
					(hide yes)
				)
			)
			(property "Author" "Antmicro"
				(at 41.91 -15.24 0)
				(effects
					(font
						(size 1.27 1.27)
						(thickness 0.15)
					)
					(justify left bottom)
					(hide yes)
				)
			)
			(property "License" "Apache-2.0"
				(at 41.91 -17.78 0)
				(effects
					(font
						(size 1.27 1.27)
						(thickness 0.15)
					)
					(justify left bottom)
					(hide yes)
				)
			)
			(symbol "Bus_RJ45_7499111121A_1_1"
				(rectangle
					(start 2.54 2.54)
					(end 25.4 -33.02)
					(stroke
						(width 0.254)
						(type default)
					)
					(fill
						(type background)
					)
				)
				(polyline
					(pts
						(xy 13.97 -19.05) (xy 20.32 -19.05)
					)
					(stroke
						(width 0.254)
						(type default)
					)
					(fill
						(type background)
					)
				)
				(polyline
					(pts
						(xy 13.97 -30.48) (xy 13.97 -19.05)
					)
					(stroke
						(width 0.254)
						(type default)
					)
					(fill
						(type background)
					)
				)
				(polyline
					(pts
						(xy 20.32 -19.05) (xy 20.32 -20.32)
					)
					(stroke
						(width 0.254)
						(type default)
					)
					(fill
						(type background)
					)
				)
				(polyline
					(pts
						(xy 20.32 -20.32) (xy 21.59 -20.32)
					)
					(stroke
						(width 0.254)
						(type default)
					)
					(fill
						(type background)
					)
				)
				(polyline
					(pts
						(xy 20.32 -29.21) (xy 21.59 -29.21)
					)
					(stroke
						(width 0.254)
						(type default)
					)
					(fill
						(type background)
					)
				)
				(polyline
					(pts
						(xy 20.32 -30.48) (xy 13.97 -30.48)
					)
					(stroke
						(width 0.254)
						(type default)
					)
					(fill
						(type background)
					)
				)
				(polyline
					(pts
						(xy 20.32 -30.48) (xy 20.32 -29.21)
					)
					(stroke
						(width 0.254)
						(type default)
					)
					(fill
						(type background)
					)
				)
				(polyline
					(pts
						(xy 21.59 -20.32) (xy 21.59 -21.59)
					)
					(stroke
						(width 0.254)
						(type default)
					)
					(fill
						(type background)
					)
				)
				(polyline
					(pts
						(xy 21.59 -21.59) (xy 22.86 -21.59)
					)
					(stroke
						(width 0.254)
						(type default)
					)
					(fill
						(type background)
					)
				)
				(polyline
					(pts
						(xy 21.59 -27.94) (xy 22.86 -27.94)
					)
					(stroke
						(width 0.254)
						(type default)
					)
					(fill
						(type background)
					)
				)
				(polyline
					(pts
						(xy 21.59 -29.21) (xy 21.59 -27.94)
					)
					(stroke
						(width 0.254)
						(type default)
					)
					(fill
						(type background)
					)
				)
				(polyline
					(pts
						(xy 22.86 -21.59) (xy 22.86 -27.94)
					)
					(stroke
						(width 0.254)
						(type default)
					)
					(fill
						(type background)
					)
				)
				(pin power_in line
					(at 0 0 0)
					(length 2.54)
					(name "VCC"
						(effects
							(font
								(size 1.27 1.27)
							)
						)
					)
					(number "9"
						(effects
							(font
								(size 1.27 1.27)
							)
						)
					)
				)
				(pin bidirectional line
					(at 0 -5.08 0)
					(length 2.54)
					(name "D1+"
						(effects
							(font
								(size 1.27 1.27)
							)
						)
					)
					(number "1"
						(effects
							(font
								(size 1.27 1.27)
							)
						)
					)
				)
				(pin bidirectional line
					(at 0 -7.62 0)
					(length 2.54)
					(name "D1-"
						(effects
							(font
								(size 1.27 1.27)
							)
						)
					)
					(number "2"
						(effects
							(font
								(size 1.27 1.27)
							)
						)
					)
				)
				(pin bidirectional line
					(at 0 -10.16 0)
					(length 2.54)
					(name "D2+"
						(effects
							(font
								(size 1.27 1.27)
							)
						)
					)
					(number "3"
						(effects
							(font
								(size 1.27 1.27)
							)
						)
					)
				)
				(pin bidirectional line
					(at 0 -12.7 0)
					(length 2.54)
					(name "D2-"
						(effects
							(font
								(size 1.27 1.27)
							)
						)
					)
					(number "6"
						(effects
							(font
								(size 1.27 1.27)
							)
						)
					)
				)
				(pin bidirectional line
					(at 0 -15.24 0)
					(length 2.54)
					(name "D3+"
						(effects
							(font
								(size 1.27 1.27)
							)
						)
					)
					(number "4"
						(effects
							(font
								(size 1.27 1.27)
							)
						)
					)
				)
				(pin bidirectional line
					(at 0 -17.78 0)
					(length 2.54)
					(name "D3-"
						(effects
							(font
								(size 1.27 1.27)
							)
						)
					)
					(number "5"
						(effects
							(font
								(size 1.27 1.27)
							)
						)
					)
				)
				(pin bidirectional line
					(at 0 -20.32 0)
					(length 2.54)
					(name "D4+"
						(effects
							(font
								(size 1.27 1.27)
							)
						)
					)
					(number "7"
						(effects
							(font
								(size 1.27 1.27)
							)
						)
					)
				)
				(pin bidirectional line
					(at 0 -22.86 0)
					(length 2.54)
					(name "D4-"
						(effects
							(font
								(size 1.27 1.27)
							)
						)
					)
					(number "8"
						(effects
							(font
								(size 1.27 1.27)
							)
						)
					)
				)
				(pin power_in line
					(at 0 -27.94 0)
					(length 2.54)
					(name "GND"
						(effects
							(font
								(size 1.27 1.27)
							)
						)
					)
					(number "10"
						(effects
							(font
								(size 1.27 1.27)
							)
						)
					)
				)
				(pin passive line
					(at 0 -30.48 0)
					(length 2.54)
					(name "~"
						(effects
							(font
								(size 1.27 1.27)
							)
						)
					)
					(number "SH"
						(effects
							(font
								(size 1.27 1.27)
							)
						)
					)
				)
				(pin passive line
					(at 0 -30.48 0)
					(length 2.54)
					(hide yes)
					(name "~"
						(effects
							(font
								(size 1.27 1.27)
							)
						)
					)
					(number "SH"
						(effects
							(font
								(size 1.27 1.27)
							)
						)
					)
				)
				(pin passive line
					(at 27.94 0 180)
					(length 2.54)
					(name "LED1_Y+"
						(effects
							(font
								(size 1.27 1.27)
							)
						)
					)
					(number "11"
						(effects
							(font
								(size 1.27 1.27)
							)
						)
					)
				)
				(pin passive line
					(at 27.94 -2.54 180)
					(length 2.54)
					(name "LED1_Y-"
						(effects
							(font
								(size 1.27 1.27)
							)
						)
					)
					(number "12"
						(effects
							(font
								(size 1.27 1.27)
							)
						)
					)
				)
				(pin passive line
					(at 27.94 -7.62 180)
					(length 2.54)
					(name "LED2_G+"
						(effects
							(font
								(size 1.27 1.27)
							)
						)
					)
					(number "13"
						(effects
							(font
								(size 1.27 1.27)
							)
						)
					)
				)
				(pin passive line
					(at 27.94 -10.16 180)
					(length 2.54)
					(name "LED2_G-"
						(effects
							(font
								(size 1.27 1.27)
							)
						)
					)
					(number "14"
						(effects
							(font
								(size 1.27 1.27)
							)
						)
					)
				)
			)
		)
	(symbol "antmicroModules:ddr5-testbed"
			(exclude_from_sim no)
			(in_bom no)
			(on_board yes)
			(property "Reference" "A"
				(at 22.86 0 0)
				(effects
					(font
						(size 1.27 1.27)
						(thickness 0.15)
					)
					(justify left bottom)
				)
			)
			(property "Value" "ddr5-testbed"
				(at 22.86 -5.08 0)
				(effects
					(font
						(size 1.27 1.27)
						(thickness 0.15)
					)
					(justify left bottom)
					(hide yes)
				)
			)
			(property "Footprint" "antmicro-footprints:DDR5-testbed"
				(at 22.86 -7.62 0)
				(effects
					(font
						(size 1.27 1.27)
						(thickness 0.15)
					)
					(justify left bottom)
					(hide yes)
				)
			)
			(property "Datasheet" ""
				(at 22.86 -10.16 0)
				(effects
					(font
						(size 1.27 1.27)
						(thickness 0.15)
					)
					(justify left bottom)
					(hide yes)
				)
			)
			(property "Description" "DDR5 testbed"
				(at 0 0 0)
				(effects
					(font
						(size 1.27 1.27)
					)
					(hide yes)
				)
			)
			(property "MPN" ""
				(at 22.86 -2.54 0)
				(effects
					(font
						(size 1.27 1.27)
						(thickness 0.15)
					)
					(justify left bottom)
				)
			)
			(property "Manufacturer" "Antmicro "
				(at 22.86 -12.7 0)
				(effects
					(font
						(size 1.27 1.27)
						(thickness 0.15)
					)
					(justify left bottom)
					(hide yes)
				)
			)
			(property "Author" "Antmicro"
				(at 22.86 -15.24 0)
				(effects
					(font
						(size 1.27 1.27)
						(thickness 0.15)
					)
					(justify left bottom)
					(hide yes)
				)
			)
			(property "License" "Apache-2.0"
				(at 22.86 -17.78 0)
				(effects
					(font
						(size 1.27 1.27)
						(thickness 0.15)
					)
					(justify left bottom)
					(hide yes)
				)
			)
			(symbol "ddr5-testbed_1_1"
				(rectangle
					(start -7.62 5.08)
					(end 7.62 -5.08)
					(stroke
						(width 0.254)
						(type default)
					)
					(fill
						(type background)
					)
				)
			)
		)
	(symbol "antmicroOscillators:Oscillator_100MHz_ASFL1"
			(exclude_from_sim no)
			(in_bom yes)
			(on_board yes)
			(property "Reference" "Y"
				(at 26.035 -1.905 0)
				(effects
					(font
						(size 1.27 1.27)
						(thickness 0.15)
					)
					(justify left bottom)
				)
			)
			(property "Value" "Oscillator_100MHz_ASFL1"
				(at 26.035 -12.065 0)
				(effects
					(font
						(size 1.27 1.27)
						(thickness 0.15)
					)
					(justify left bottom)
					(hide yes)
				)
			)
			(property "Footprint" "antmicro-footprints:Oscillator_SMD_Abracon_ASFL1-4Pin_5.0x3.2mm"
				(at 26.035 -14.605 0)
				(effects
					(font
						(size 1.27 1.27)
						(thickness 0.15)
					)
					(justify left bottom)
					(hide yes)
				)
			)
			(property "Datasheet" "https://abracon.com/Oscillators/ASFL1.pdf"
				(at 26.035 -17.145 0)
				(effects
					(font
						(size 1.27 1.27)
						(thickness 0.15)
					)
					(justify left bottom)
					(hide yes)
				)
			)
			(property "Description" "Oscillator, 100 MHz, 100 ppm, SMT, 5mm x 3.2mm, 3.3 V, ASFL1 Series"
				(at 0 0 0)
				(effects
					(font
						(size 1.27 1.27)
					)
					(hide yes)
				)
			)
			(property "MPN" "ASFL1-100.000MHZ-L-T"
				(at 26.035 -4.445 0)
				(effects
					(font
						(size 1.27 1.27)
						(thickness 0.15)
					)
					(justify left bottom)
				)
			)
			(property "Manufacturer" "Abracon"
				(at 26.035 -6.985 0)
				(effects
					(font
						(size 1.27 1.27)
						(thickness 0.15)
					)
					(justify left bottom)
					(hide yes)
				)
			)
			(property "Val" "100 MHz"
				(at 26.035 -9.525 0)
				(effects
					(font
						(size 1.27 1.27)
						(thickness 0.15)
					)
					(justify left bottom)
				)
			)
			(property "Author" "Antmicro"
				(at 26.035 -19.685 0)
				(effects
					(font
						(size 1.27 1.27)
						(thickness 0.15)
					)
					(justify left bottom)
					(hide yes)
				)
			)
			(property "License" "Apache-2.0"
				(at 26.035 -22.225 0)
				(effects
					(font
						(size 1.27 1.27)
						(thickness 0.15)
					)
					(justify left bottom)
					(hide yes)
				)
			)
			(property "ki_keywords" "OSCILLATOR"
				(at 0 0 0)
				(effects
					(font
						(size 1.27 1.27)
					)
					(hide yes)
				)
			)
			(symbol "Oscillator_100MHz_ASFL1_1_1"
				(rectangle
					(start 2.54 2.54)
					(end 16.51 -7.62)
					(stroke
						(width 0.254)
						(type default)
					)
					(fill
						(type background)
					)
				)
				(polyline
					(pts
						(xy 7.62 -1.27) (xy 8.255 -1.27) (xy 8.255 0) (xy 8.89 0) (xy 8.89 -1.27) (xy 9.525 -1.27) (xy 9.525 0)
						(xy 10.16 0) (xy 10.16 -1.27)
					)
					(stroke
						(width 0.254)
						(type default)
					)
					(fill
						(type background)
					)
				)
				(pin power_in line
					(at 0 0 0)
					(length 2.54)
					(name "VDD"
						(effects
							(font
								(size 1.27 1.27)
							)
						)
					)
					(number "4"
						(effects
							(font
								(size 1.27 1.27)
							)
						)
					)
				)
				(pin input line
					(at 0 -2.54 0)
					(length 2.54)
					(name "EN"
						(effects
							(font
								(size 1.27 1.27)
							)
						)
					)
					(number "1"
						(effects
							(font
								(size 1.27 1.27)
							)
						)
					)
				)
				(pin power_in line
					(at 0 -5.08 0)
					(length 2.54)
					(name "GND"
						(effects
							(font
								(size 1.27 1.27)
							)
						)
					)
					(number "2"
						(effects
							(font
								(size 1.27 1.27)
							)
						)
					)
				)
				(pin output line
					(at 19.05 0 180)
					(length 2.54)
					(name "OUT"
						(effects
							(font
								(size 1.27 1.27)
							)
						)
					)
					(number "3"
						(effects
							(font
								(size 1.27 1.27)
							)
						)
					)
				)
			)
		)
	(symbol "antmicroPMICPowerDistributionSwitchesLoadDrivers:SLG59M1457V"
			(exclude_from_sim no)
			(in_bom yes)
			(on_board yes)
			(property "Reference" "U"
				(at 31.75 -2.54 0)
				(effects
					(font
						(size 1.27 1.27)
						(thickness 0.15)
					)
					(justify left bottom)
				)
			)
			(property "Value" "SLG59M1457V"
				(at 31.75 -7.62 0)
				(effects
					(font
						(size 1.27 1.27)
						(thickness 0.15)
					)
					(justify left bottom)
					(hide yes)
				)
			)
			(property "Footprint" "antmicro-footprints:RENESAS-TDFN-8-1.5x2.0mm_P0.5mm"
				(at 31.75 -10.16 0)
				(effects
					(font
						(size 1.27 1.27)
						(thickness 0.15)
					)
					(justify left bottom)
					(hide yes)
				)
			)
			(property "Datasheet" "https://www.renesas.com/eu/en/document/dst/slg59m1457v-datasheet?r=1564331"
				(at 31.75 -12.7 0)
				(effects
					(font
						(size 1.27 1.27)
						(thickness 0.15)
					)
					(justify left bottom)
					(hide yes)
				)
			)
			(property "Description" "Power distribution switch/load driver"
				(at 0 0 0)
				(effects
					(font
						(size 1.27 1.27)
					)
					(hide yes)
				)
			)
			(property "Manufacturer" "Dialog Semiconductor"
				(at 31.75 -15.24 0)
				(effects
					(font
						(size 1.27 1.27)
						(thickness 0.15)
					)
					(justify left bottom)
					(hide yes)
				)
			)
			(property "MPN" "SLG59M1457V"
				(at 31.75 -5.08 0)
				(effects
					(font
						(size 1.27 1.27)
						(thickness 0.15)
					)
					(justify left bottom)
				)
			)
			(property "Author" "Antmicro"
				(at 31.75 -17.78 0)
				(effects
					(font
						(size 1.27 1.27)
						(thickness 0.15)
					)
					(justify left bottom)
					(hide yes)
				)
			)
			(property "License" "Apache-2.0"
				(at 31.75 -20.32 0)
				(effects
					(font
						(size 1.27 1.27)
						(thickness 0.15)
					)
					(justify left bottom)
					(hide yes)
				)
			)
			(property "ki_keywords" "SMT, PMIC, IC, DRIVER, POWER"
				(at 0 0 0)
				(effects
					(font
						(size 1.27 1.27)
					)
					(hide yes)
				)
			)
			(symbol "SLG59M1457V_1_1"
				(rectangle
					(start 2.54 2.54)
					(end 15.24 -7.62)
					(stroke
						(width 0.254)
						(type default)
					)
					(fill
						(type background)
					)
				)
				(pin input line
					(at 0 0 0)
					(length 2.54)
					(name "ON"
						(effects
							(font
								(size 1.27 1.27)
							)
						)
					)
					(number "2"
						(effects
							(font
								(size 1.27 1.27)
							)
						)
					)
				)
				(pin power_in line
					(at 0 -2.54 0)
					(length 2.54)
					(name "IN"
						(effects
							(font
								(size 1.27 1.27)
							)
						)
					)
					(number "3"
						(effects
							(font
								(size 1.27 1.27)
							)
						)
					)
				)
				(pin power_in line
					(at 0 -5.08 0)
					(length 2.54)
					(name "VDD"
						(effects
							(font
								(size 1.27 1.27)
							)
						)
					)
					(number "1"
						(effects
							(font
								(size 1.27 1.27)
							)
						)
					)
				)
				(pin power_out line
					(at 17.78 0 180)
					(length 2.54)
					(name "OUT"
						(effects
							(font
								(size 1.27 1.27)
							)
						)
					)
					(number "5"
						(effects
							(font
								(size 1.27 1.27)
							)
						)
					)
				)
				(pin input line
					(at 17.78 -2.54 180)
					(length 2.54)
					(name "CAP"
						(effects
							(font
								(size 1.27 1.27)
							)
						)
					)
					(number "7"
						(effects
							(font
								(size 1.27 1.27)
							)
						)
					)
				)
				(pin passive line
					(at 17.78 -5.08 180)
					(length 2.54)
					(name "GND"
						(effects
							(font
								(size 1.27 1.27)
							)
						)
					)
					(number "8"
						(effects
							(font
								(size 1.27 1.27)
							)
						)
					)
				)
			)
		)
	(symbol "antmicroPMICPowerSequencers:LM3881"
			(exclude_from_sim no)
			(in_bom yes)
			(on_board yes)
			(property "Reference" "U"
				(at 30.48 -2.54 0)
				(effects
					(font
						(size 1.27 1.27)
						(thickness 0.15)
					)
					(justify left bottom)
				)
			)
			(property "Value" "LM3881"
				(at 30.48 -7.62 0)
				(effects
					(font
						(size 1.27 1.27)
						(thickness 0.15)
					)
					(justify left bottom)
					(hide yes)
				)
			)
			(property "Footprint" "antmicro-footprints:VSSOP-8_3x3mm_P0.65mm"
				(at 30.48 -10.16 0)
				(effects
					(font
						(size 1.27 1.27)
						(thickness 0.15)
					)
					(justify left bottom)
					(hide yes)
				)
			)
			(property "Datasheet" "http://www.ti.com/lit/ds/symlink/lm3881.pdf"
				(at 30.48 -12.7 0)
				(effects
					(font
						(size 1.27 1.27)
						(thickness 0.15)
					)
					(justify left bottom)
					(hide yes)
				)
			)
			(property "Description" "Power Sequencer, 3-Monitors, 2.7V-5.5Vin,VSSOP-8"
				(at 0 0 0)
				(effects
					(font
						(size 1.27 1.27)
					)
					(hide yes)
				)
			)
			(property "Manufacturer" "Texas Instruments"
				(at 30.48 -15.24 0)
				(effects
					(font
						(size 1.27 1.27)
						(thickness 0.15)
					)
					(justify left bottom)
					(hide yes)
				)
			)
			(property "MPN" "LM3881MME/NOPB"
				(at 30.48 -5.08 0)
				(effects
					(font
						(size 1.27 1.27)
						(thickness 0.15)
					)
					(justify left bottom)
				)
			)
			(property "Author" "Antmicro"
				(at 30.48 -17.78 0)
				(effects
					(font
						(size 1.27 1.27)
						(thickness 0.15)
					)
					(justify left bottom)
					(hide yes)
				)
			)
			(property "License" "Apache-2.0"
				(at 30.48 -20.32 0)
				(effects
					(font
						(size 1.27 1.27)
						(thickness 0.15)
					)
					(justify left bottom)
					(hide yes)
				)
			)
			(property "ki_keywords" "SMT, PMIC, IC, POWER, SEQUENCER"
				(at 0 0 0)
				(effects
					(font
						(size 1.27 1.27)
					)
					(hide yes)
				)
			)
			(symbol "LM3881_1_1"
				(rectangle
					(start 2.54 2.54)
					(end 13.97 -10.16)
					(stroke
						(width 0.254)
						(type default)
					)
					(fill
						(type background)
					)
				)
				(pin power_in line
					(at 0 0 0)
					(length 2.54)
					(name "VCC"
						(effects
							(font
								(size 1.27 1.27)
							)
						)
					)
					(number "1"
						(effects
							(font
								(size 1.27 1.27)
							)
						)
					)
				)
				(pin passive line
					(at 0 -2.54 0)
					(length 2.54)
					(name "EN"
						(effects
							(font
								(size 1.27 1.27)
							)
						)
					)
					(number "2"
						(effects
							(font
								(size 1.27 1.27)
							)
						)
					)
				)
				(pin input line
					(at 0 -5.08 0)
					(length 2.54)
					(name "INV"
						(effects
							(font
								(size 1.27 1.27)
							)
						)
					)
					(number "4"
						(effects
							(font
								(size 1.27 1.27)
							)
						)
					)
				)
				(pin passive line
					(at 0 -7.62 0)
					(length 2.54)
					(name "TADJ"
						(effects
							(font
								(size 1.27 1.27)
							)
						)
					)
					(number "5"
						(effects
							(font
								(size 1.27 1.27)
							)
						)
					)
				)
				(pin open_collector line
					(at 16.51 0 180)
					(length 2.54)
					(name "FLAG1"
						(effects
							(font
								(size 1.27 1.27)
							)
						)
					)
					(number "8"
						(effects
							(font
								(size 1.27 1.27)
							)
						)
					)
				)
				(pin open_collector line
					(at 16.51 -2.54 180)
					(length 2.54)
					(name "FLAG2"
						(effects
							(font
								(size 1.27 1.27)
							)
						)
					)
					(number "7"
						(effects
							(font
								(size 1.27 1.27)
							)
						)
					)
				)
				(pin open_collector line
					(at 16.51 -5.08 180)
					(length 2.54)
					(name "FLAG3"
						(effects
							(font
								(size 1.27 1.27)
							)
						)
					)
					(number "6"
						(effects
							(font
								(size 1.27 1.27)
							)
						)
					)
				)
				(pin power_in line
					(at 16.51 -7.62 180)
					(length 2.54)
					(name "GND"
						(effects
							(font
								(size 1.27 1.27)
							)
						)
					)
					(number "3"
						(effects
							(font
								(size 1.27 1.27)
							)
						)
					)
				)
			)
		)
	(symbol "antmicroPMICVoltageRegulatorsDCDCSwitchingControllers:TPS65296RJE"
			(exclude_from_sim no)
			(in_bom yes)
			(on_board yes)
			(property "Reference" "U"
				(at 40.64 -2.54 0)
				(effects
					(font
						(size 1.27 1.27)
						(thickness 0.15)
					)
					(justify left bottom)
				)
			)
			(property "Value" "TPS65296"
				(at 40.64 -7.62 0)
				(effects
					(font
						(size 1.27 1.27)
						(thickness 0.15)
					)
					(justify left bottom)
					(hide yes)
				)
			)
			(property "Footprint" "antmicro-footprints:VQFN-18_3x3x1mm_P0.5mm"
				(at 40.64 -10.16 0)
				(effects
					(font
						(size 1.27 1.27)
						(thickness 0.15)
					)
					(justify left bottom)
					(hide yes)
				)
			)
			(property "Datasheet" "https://www.ti.com/lit/ds/symlink/tps65296.pdf"
				(at 40.64 -12.7 0)
				(effects
					(font
						(size 1.27 1.27)
						(thickness 0.15)
					)
					(justify left bottom)
					(hide yes)
				)
			)
			(property "Description" "DC/DC switching voltage regulator"
				(at 0 0 0)
				(effects
					(font
						(size 1.27 1.27)
					)
					(hide yes)
				)
			)
			(property "Manufacturer" "Texas Instruments"
				(at 40.64 -15.24 0)
				(effects
					(font
						(size 1.27 1.27)
						(thickness 0.15)
					)
					(justify left bottom)
					(hide yes)
				)
			)
			(property "MPN" "TPS65296RJER"
				(at 40.64 -5.08 0)
				(effects
					(font
						(size 1.27 1.27)
						(thickness 0.15)
					)
					(justify left bottom)
				)
			)
			(property "Author" "Antmicro"
				(at 40.64 -17.78 0)
				(effects
					(font
						(size 1.27 1.27)
						(thickness 0.15)
					)
					(justify left bottom)
					(hide yes)
				)
			)
			(property "License" "Apache-2.0"
				(at 40.64 -20.32 0)
				(effects
					(font
						(size 1.27 1.27)
						(thickness 0.15)
					)
					(justify left bottom)
					(hide yes)
				)
			)
			(property "ki_keywords" "SMT, PMIC, IC, SWITCHING, VOLTAGE, REGULATOR, DC-DC"
				(at 0 0 0)
				(effects
					(font
						(size 1.27 1.27)
					)
					(hide yes)
				)
			)
			(symbol "TPS65296RJE_1_1"
				(rectangle
					(start 2.54 2.54)
					(end 25.4 -52.705)
					(stroke
						(width 0.254)
						(type default)
					)
					(fill
						(type background)
					)
				)
				(pin input line
					(at 0 0 0)
					(length 2.54)
					(name "VDDEN"
						(effects
							(font
								(size 1.27 1.27)
							)
						)
					)
					(number "11"
						(effects
							(font
								(size 1.27 1.27)
							)
						)
					)
				)
				(pin input line
					(at 0 -2.54 0)
					(length 2.54)
					(name "VDDQEN"
						(effects
							(font
								(size 1.27 1.27)
							)
						)
					)
					(number "10"
						(effects
							(font
								(size 1.27 1.27)
							)
						)
					)
				)
				(pin input line
					(at 0 -5.08 0)
					(length 2.54)
					(name "PVIN"
						(effects
							(font
								(size 1.27 1.27)
							)
						)
					)
					(number "7"
						(effects
							(font
								(size 1.27 1.27)
							)
						)
					)
				)
				(pin input line
					(at 0 -22.86 0)
					(length 2.54)
					(name "VCC_5V"
						(effects
							(font
								(size 1.27 1.27)
							)
						)
					)
					(number "13"
						(effects
							(font
								(size 1.27 1.27)
							)
						)
					)
				)
				(pin input line
					(at 0 -25.4 0)
					(length 2.54)
					(name "PIN_VDD1"
						(effects
							(font
								(size 1.27 1.27)
							)
						)
					)
					(number "14"
						(effects
							(font
								(size 1.27 1.27)
							)
						)
					)
				)
				(pin input line
					(at 0 -40.64 0)
					(length 2.54)
					(name "VLDOIN"
						(effects
							(font
								(size 1.27 1.27)
							)
						)
					)
					(number "1"
						(effects
							(font
								(size 1.27 1.27)
							)
						)
					)
				)
				(pin input line
					(at 0 -48.26 0)
					(length 2.54)
					(name "PGND"
						(effects
							(font
								(size 1.27 1.27)
							)
						)
					)
					(number "9"
						(effects
							(font
								(size 1.27 1.27)
							)
						)
					)
				)
				(pin input line
					(at 0 -50.8 0)
					(length 2.54)
					(name "PGND_VDD1"
						(effects
							(font
								(size 1.27 1.27)
							)
						)
					)
					(number "16"
						(effects
							(font
								(size 1.27 1.27)
							)
						)
					)
				)
				(pin input line
					(at 27.94 0 180)
					(length 2.54)
					(name "PGOOD"
						(effects
							(font
								(size 1.27 1.27)
							)
						)
					)
					(number "8"
						(effects
							(font
								(size 1.27 1.27)
							)
						)
					)
				)
				(pin input line
					(at 27.94 -2.54 180)
					(length 2.54)
					(name "SW_VDD1"
						(effects
							(font
								(size 1.27 1.27)
							)
						)
					)
					(number "15"
						(effects
							(font
								(size 1.27 1.27)
							)
						)
					)
				)
				(pin input line
					(at 27.94 -5.08 180)
					(length 2.54)
					(name "VDD1SNS"
						(effects
							(font
								(size 1.27 1.27)
							)
						)
					)
					(number "12"
						(effects
							(font
								(size 1.27 1.27)
							)
						)
					)
				)
				(pin input line
					(at 27.94 -15.24 180)
					(length 2.54)
					(name "BST"
						(effects
							(font
								(size 1.27 1.27)
							)
						)
					)
					(number "18"
						(effects
							(font
								(size 1.27 1.27)
							)
						)
					)
				)
				(pin input line
					(at 27.94 -22.86 180)
					(length 2.54)
					(name "SW"
						(effects
							(font
								(size 1.27 1.27)
							)
						)
					)
					(number "17"
						(effects
							(font
								(size 1.27 1.27)
							)
						)
					)
				)
				(pin input line
					(at 27.94 -25.4 180)
					(length 2.54)
					(name "VDD2SNS"
						(effects
							(font
								(size 1.27 1.27)
							)
						)
					)
					(number "5"
						(effects
							(font
								(size 1.27 1.27)
							)
						)
					)
				)
				(pin input line
					(at 27.94 -35.56 180)
					(length 2.54)
					(name "VDDQ"
						(effects
							(font
								(size 1.27 1.27)
							)
						)
					)
					(number "2"
						(effects
							(font
								(size 1.27 1.27)
							)
						)
					)
				)
				(pin input line
					(at 27.94 -38.1 180)
					(length 2.54)
					(name "VDDQSNS"
						(effects
							(font
								(size 1.27 1.27)
							)
						)
					)
					(number "4"
						(effects
							(font
								(size 1.27 1.27)
							)
						)
					)
				)
				(pin input line
					(at 27.94 -43.18 180)
					(length 2.54)
					(name "VDDQREF"
						(effects
							(font
								(size 1.27 1.27)
							)
						)
					)
					(number "6"
						(effects
							(font
								(size 1.27 1.27)
							)
						)
					)
				)
				(pin input line
					(at 27.94 -50.8 180)
					(length 2.54)
					(name "AGND"
						(effects
							(font
								(size 1.27 1.27)
							)
						)
					)
					(number "3"
						(effects
							(font
								(size 1.27 1.27)
							)
						)
					)
				)
			)
		)
	(symbol "antmicroPMICVoltageRegulatorsLinear:MIC61300YML"
			(exclude_from_sim no)
			(in_bom yes)
			(on_board yes)
			(property "Reference" "U"
				(at 40.64 -3.81 0)
				(effects
					(font
						(size 1.27 1.27)
						(thickness 0.15)
					)
					(justify left bottom)
				)
			)
			(property "Value" "MIC61300YML"
				(at 40.64 -8.89 0)
				(effects
					(font
						(size 1.27 1.27)
						(thickness 0.15)
					)
					(justify left bottom)
					(hide yes)
				)
			)
			(property "Footprint" "antmicro-footprints:DFN-10-1EP_3x3mm"
				(at 40.64 -11.43 0)
				(effects
					(font
						(size 1.27 1.27)
						(thickness 0.15)
					)
					(justify left bottom)
					(hide yes)
				)
			)
			(property "Datasheet" "https://ww1.microchip.com/downloads/en/DeviceDoc/mic61300.pdf"
				(at 40.64 -13.97 0)
				(effects
					(font
						(size 1.27 1.27)
						(thickness 0.15)
					)
					(justify left bottom)
					(hide yes)
				)
			)
			(property "Description" "Linear voltage regulator"
				(at 0 0 0)
				(effects
					(font
						(size 1.27 1.27)
					)
					(hide yes)
				)
			)
			(property "MPN" "MIC61300YML-TR"
				(at 40.64 -6.35 0)
				(effects
					(font
						(size 1.27 1.27)
						(thickness 0.15)
					)
					(justify left bottom)
				)
			)
			(property "Manufacturer" "Microchip Technology"
				(at 40.64 -16.51 0)
				(effects
					(font
						(size 1.27 1.27)
						(thickness 0.15)
					)
					(justify left bottom)
					(hide yes)
				)
			)
			(property "Author" "Antmicro"
				(at 40.64 -19.05 0)
				(effects
					(font
						(size 1.27 1.27)
						(thickness 0.15)
					)
					(justify left bottom)
					(hide yes)
				)
			)
			(property "License" "Apache-2.0"
				(at 40.64 -21.59 0)
				(effects
					(font
						(size 1.27 1.27)
						(thickness 0.15)
					)
					(justify left bottom)
					(hide yes)
				)
			)
			(property "ki_keywords" "SMT, LDO, IC, LINEAR, REGULATOR"
				(at 0 0 0)
				(effects
					(font
						(size 1.27 1.27)
					)
					(hide yes)
				)
			)
			(symbol "MIC61300YML_1_1"
				(rectangle
					(start 2.54 2.54)
					(end 15.24 -10.16)
					(stroke
						(width 0.254)
						(type default)
					)
					(fill
						(type background)
					)
				)
				(text ""
					(at 2.54 -15.24 0)
					(effects
						(font
							(size 1.27 1.27)
							(thickness 0.15)
						)
						(justify left bottom)
					)
				)
				(pin power_in line
					(at 0 0 0)
					(length 2.54)
					(name "IN"
						(effects
							(font
								(size 1.27 1.27)
							)
						)
					)
					(number "1"
						(effects
							(font
								(size 1.27 1.27)
							)
						)
					)
				)
				(pin passive line
					(at 0 0 0)
					(length 2.54)
					(hide yes)
					(name "IN"
						(effects
							(font
								(size 1.27 1.27)
							)
						)
					)
					(number "2"
						(effects
							(font
								(size 1.27 1.27)
							)
						)
					)
				)
				(pin input line
					(at 0 -2.54 0)
					(length 2.54)
					(name "EN"
						(effects
							(font
								(size 1.27 1.27)
							)
						)
					)
					(number "4"
						(effects
							(font
								(size 1.27 1.27)
							)
						)
					)
				)
				(pin passive line
					(at 0 -5.08 0)
					(length 2.54)
					(name "CP"
						(effects
							(font
								(size 1.27 1.27)
							)
						)
					)
					(number "7"
						(effects
							(font
								(size 1.27 1.27)
							)
						)
					)
				)
				(pin passive line
					(at 0 -7.62 0)
					(length 2.54)
					(hide yes)
					(name "GND"
						(effects
							(font
								(size 1.27 1.27)
							)
						)
					)
					(number "11"
						(effects
							(font
								(size 1.27 1.27)
							)
						)
					)
				)
				(pin passive line
					(at 0 -7.62 0)
					(length 2.54)
					(name "GND"
						(effects
							(font
								(size 1.27 1.27)
							)
						)
					)
					(number "3"
						(effects
							(font
								(size 1.27 1.27)
							)
						)
					)
				)
				(pin no_connect line
					(at 7.62 -10.16 90)
					(length 2.54)
					(hide yes)
					(name "NC"
						(effects
							(font
								(size 1.27 1.27)
							)
						)
					)
					(number "5"
						(effects
							(font
								(size 1.27 1.27)
							)
						)
					)
				)
				(pin no_connect line
					(at 10.16 -10.16 90)
					(length 2.54)
					(hide yes)
					(name "NC"
						(effects
							(font
								(size 1.27 1.27)
							)
						)
					)
					(number "6"
						(effects
							(font
								(size 1.27 1.27)
							)
						)
					)
				)
				(pin power_out line
					(at 17.78 0 180)
					(length 2.54)
					(name "OUT"
						(effects
							(font
								(size 1.27 1.27)
							)
						)
					)
					(number "10"
						(effects
							(font
								(size 1.27 1.27)
							)
						)
					)
				)
				(pin passive line
					(at 17.78 0 180)
					(length 2.54)
					(hide yes)
					(name "OUT"
						(effects
							(font
								(size 1.27 1.27)
							)
						)
					)
					(number "9"
						(effects
							(font
								(size 1.27 1.27)
							)
						)
					)
				)
				(pin input line
					(at 17.78 -7.62 180)
					(length 2.54)
					(name "FB"
						(effects
							(font
								(size 1.27 1.27)
							)
						)
					)
					(number "8"
						(effects
							(font
								(size 1.27 1.27)
							)
						)
					)
				)
			)
		)
	(symbol "antmicroPMICVoltageRegulatorsLinear:TPS54561QDPRRQ1"
			(exclude_from_sim no)
			(in_bom yes)
			(on_board yes)
			(property "Reference" "U"
				(at 38.1 -2.54 0)
				(effects
					(font
						(size 1.27 1.27)
						(thickness 0.15)
					)
					(justify left bottom)
				)
			)
			(property "Value" "TPS54561QDPRRQ1"
				(at 38.1 -5.08 0)
				(effects
					(font
						(size 1.27 1.27)
						(thickness 0.15)
					)
					(justify left bottom)
				)
			)
			(property "Footprint" "antmicro-footprints:WSON-10-1EP_4x4mm_P0.8mm_EP2.6x3mm"
				(at 38.1 -7.62 0)
				(effects
					(font
						(size 1.27 1.27)
						(thickness 0.15)
					)
					(justify left bottom)
					(hide yes)
				)
			)
			(property "Datasheet" "https://www.ti.com/lit/ds/symlink/tps54561-q1.pdf?ts=1678720110394&ref_url=https%253A%252F%252Fwww.google.com%252F"
				(at 38.1 -10.16 0)
				(effects
					(font
						(size 1.27 1.27)
						(thickness 0.15)
					)
					(justify left bottom)
					(hide yes)
				)
			)
			(property "Description" "4.5-V to 60-V Input, 5-A, Step-Down DC-DC Converter"
				(at 0 0 0)
				(effects
					(font
						(size 1.27 1.27)
					)
					(hide yes)
				)
			)
			(property "Manufacturer" "Texas Instruments"
				(at 38.1 -12.7 0)
				(effects
					(font
						(size 1.27 1.27)
						(thickness 0.15)
					)
					(justify left bottom)
					(hide yes)
				)
			)
			(property "MPN" "TPS54561QDPRRQ1"
				(at 38.1 -15.24 0)
				(effects
					(font
						(size 1.27 1.27)
						(thickness 0.15)
					)
					(justify left bottom)
					(hide yes)
				)
			)
			(property "Author" "Antmicro"
				(at 38.1 -17.78 0)
				(effects
					(font
						(size 1.27 1.27)
						(thickness 0.15)
					)
					(justify left bottom)
					(hide yes)
				)
			)
			(property "License" "Apache-2.0"
				(at 38.1 -20.32 0)
				(effects
					(font
						(size 1.27 1.27)
						(thickness 0.15)
					)
					(justify left bottom)
					(hide yes)
				)
			)
			(symbol "TPS54561QDPRRQ1_1_1"
				(rectangle
					(start 2.54 2.54)
					(end 22.86 -21.59)
					(stroke
						(width 0.254)
						(type default)
					)
					(fill
						(type background)
					)
				)
				(pin passive line
					(at 0 0 0)
					(length 2.54)
					(name "VDD"
						(effects
							(font
								(size 1.27 1.27)
							)
						)
					)
					(number "2"
						(effects
							(font
								(size 1.27 1.27)
							)
						)
					)
				)
				(pin passive line
					(at 0 -2.54 0)
					(length 2.54)
					(name "EN"
						(effects
							(font
								(size 1.27 1.27)
							)
						)
					)
					(number "3"
						(effects
							(font
								(size 1.27 1.27)
							)
						)
					)
				)
				(pin passive line
					(at 0 -7.62 0)
					(length 2.54)
					(name "RT/CLK"
						(effects
							(font
								(size 1.27 1.27)
							)
						)
					)
					(number "5"
						(effects
							(font
								(size 1.27 1.27)
							)
						)
					)
				)
				(pin passive line
					(at 0 -10.16 0)
					(length 2.54)
					(name "SS/TR"
						(effects
							(font
								(size 1.27 1.27)
							)
						)
					)
					(number "4"
						(effects
							(font
								(size 1.27 1.27)
							)
						)
					)
				)
				(pin passive line
					(at 0 -19.05 0)
					(length 2.54)
					(hide yes)
					(name "GND"
						(effects
							(font
								(size 1.27 1.27)
							)
						)
					)
					(number "11"
						(effects
							(font
								(size 1.27 1.27)
							)
						)
					)
				)
				(pin power_in line
					(at 0 -19.05 0)
					(length 2.54)
					(name "GND"
						(effects
							(font
								(size 1.27 1.27)
							)
						)
					)
					(number "8"
						(effects
							(font
								(size 1.27 1.27)
							)
						)
					)
				)
				(pin passive line
					(at 25.4 0 180)
					(length 2.54)
					(name "PWRGD"
						(effects
							(font
								(size 1.27 1.27)
							)
						)
					)
					(number "10"
						(effects
							(font
								(size 1.27 1.27)
							)
						)
					)
				)
				(pin passive line
					(at 25.4 -2.54 180)
					(length 2.54)
					(name "BOOT"
						(effects
							(font
								(size 1.27 1.27)
							)
						)
					)
					(number "1"
						(effects
							(font
								(size 1.27 1.27)
							)
						)
					)
				)
				(pin passive line
					(at 25.4 -7.62 180)
					(length 2.54)
					(name "SW"
						(effects
							(font
								(size 1.27 1.27)
							)
						)
					)
					(number "9"
						(effects
							(font
								(size 1.27 1.27)
							)
						)
					)
				)
				(pin passive line
					(at 25.4 -13.97 180)
					(length 2.54)
					(name "FB"
						(effects
							(font
								(size 1.27 1.27)
							)
						)
					)
					(number "6"
						(effects
							(font
								(size 1.27 1.27)
							)
						)
					)
				)
				(pin passive line
					(at 25.4 -19.05 180)
					(length 2.54)
					(name "COMP"
						(effects
							(font
								(size 1.27 1.27)
							)
						)
					)
					(number "7"
						(effects
							(font
								(size 1.27 1.27)
							)
						)
					)
				)
			)
		)
	(symbol "antmicroPushbuttonSwitches:SW_B3U-1000P_SMD"
			(pin_names
				(hide yes)
			)
			(exclude_from_sim no)
			(in_bom yes)
			(on_board yes)
			(property "Reference" "SW"
				(at 25.4 -2.54 0)
				(effects
					(font
						(size 1.27 1.27)
						(thickness 0.15)
					)
					(justify left bottom)
				)
			)
			(property "Value" "SW_B3U-1000P_SMD"
				(at 25.4 -5.08 0)
				(effects
					(font
						(size 1.27 1.27)
						(thickness 0.15)
					)
					(justify left bottom)
					(hide yes)
				)
			)
			(property "Footprint" "antmicro-footprints:SW_B3U-1000P_SMD"
				(at 25.4 -7.62 0)
				(effects
					(font
						(size 1.27 1.27)
						(thickness 0.15)
					)
					(justify left bottom)
					(hide yes)
				)
			)
			(property "Datasheet" "https://omronfs.omron.com/en_US/ecb/products/pdf/en-b3u.pdf"
				(at 25.4 -10.16 0)
				(effects
					(font
						(size 1.27 1.27)
						(thickness 0.15)
					)
					(justify left bottom)
					(hide yes)
				)
			)
			(property "Description" "Tactile Switch, B3U, Top Actuated, Surface Mount, Round Button, 153 gf, 50mA at 12VDC"
				(at 0 0 0)
				(effects
					(font
						(size 1.27 1.27)
					)
					(hide yes)
				)
			)
			(property "MPN" "B3U-1000P"
				(at 25.4 -12.7 0)
				(effects
					(font
						(size 1.27 1.27)
						(thickness 0.15)
					)
					(justify left bottom)
				)
			)
			(property "Manufacturer" "Omron"
				(at 25.4 -15.24 0)
				(effects
					(font
						(size 1.27 1.27)
						(thickness 0.15)
					)
					(justify left bottom)
					(hide yes)
				)
			)
			(property "Author" "Antmicro"
				(at 25.4 -17.78 0)
				(effects
					(font
						(size 1.27 1.27)
						(thickness 0.15)
					)
					(justify left bottom)
					(hide yes)
				)
			)
			(property "License" "Apache-2.0"
				(at 25.4 -20.32 0)
				(effects
					(font
						(size 1.27 1.27)
						(thickness 0.15)
					)
					(justify left bottom)
					(hide yes)
				)
			)
			(property "ki_keywords" "VERTICAL, SMT, SWITCH, MECHANICAL, TACTILE"
				(at 0 0 0)
				(effects
					(font
						(size 1.27 1.27)
					)
					(hide yes)
				)
			)
			(symbol "SW_B3U-1000P_SMD_1_1"
				(polyline
					(pts
						(xy 2.54 0) (xy 3.302 0)
					)
					(stroke
						(width 0.254)
						(type default)
					)
					(fill
						(type none)
					)
				)
				(polyline
					(pts
						(xy 3.302 1.27) (xy 6.858 1.27)
					)
					(stroke
						(width 0.254)
						(type default)
					)
					(fill
						(type none)
					)
				)
				(circle
					(center 3.556 0)
					(radius 0.254)
					(stroke
						(width 0.254)
						(type default)
					)
					(fill
						(type none)
					)
				)
				(polyline
					(pts
						(xy 4.064 2.794) (xy 6.096 2.794)
					)
					(stroke
						(width 0.254)
						(type default)
					)
					(fill
						(type none)
					)
				)
				(polyline
					(pts
						(xy 5.08 1.27) (xy 5.08 2.794)
					)
					(stroke
						(width 0.254)
						(type default)
					)
					(fill
						(type none)
					)
				)
				(circle
					(center 6.604 0)
					(radius 0.254)
					(stroke
						(width 0.254)
						(type default)
					)
					(fill
						(type none)
					)
				)
				(polyline
					(pts
						(xy 7.62 0) (xy 6.858 0)
					)
					(stroke
						(width 0.254)
						(type default)
					)
					(fill
						(type none)
					)
				)
				(pin passive line
					(at 0 0 0)
					(length 2.54)
					(name "1"
						(effects
							(font
								(size 1.27 1.27)
							)
						)
					)
					(number "1"
						(effects
							(font
								(size 1.27 1.27)
							)
						)
					)
				)
				(pin passive line
					(at 10.16 0 180)
					(length 2.54)
					(name "2"
						(effects
							(font
								(size 1.27 1.27)
							)
						)
					)
					(number "2"
						(effects
							(font
								(size 1.27 1.27)
							)
						)
					)
				)
			)
		)
	(symbol "antmicroResistors0402:R_0R_0402"
			(pin_numbers
				(hide yes)
			)
			(pin_names
				(hide yes)
			)
			(exclude_from_sim no)
			(in_bom yes)
			(on_board yes)
			(property "Reference" "R"
				(at 20.32 -5.08 0)
				(effects
					(font
						(size 1.27 1.27)
						(thickness 0.15)
					)
					(justify left bottom)
				)
			)
			(property "Value" "R_0R_0402"
				(at 20.32 -12.7 0)
				(effects
					(font
						(size 1.27 1.27)
						(thickness 0.15)
					)
					(justify left bottom)
					(hide yes)
				)
			)
			(property "Footprint" "antmicro-footprints:R_0402_1005Metric"
				(at 20.32 -15.24 0)
				(effects
					(font
						(size 1.27 1.27)
						(thickness 0.15)
					)
					(justify left bottom)
					(hide yes)
				)
			)
			(property "Datasheet" "https://industrial.panasonic.com/cdbs/www-data/pdf/RDA0000/AOA0000C301.pdf"
				(at 20.32 -17.78 0)
				(effects
					(font
						(size 1.27 1.27)
						(thickness 0.15)
					)
					(justify left bottom)
					(hide yes)
				)
			)
			(property "Description" "0R resistor in 0402 package with unspecified tolerance"
				(at 0 0 0)
				(effects
					(font
						(size 1.27 1.27)
					)
					(hide yes)
				)
			)
			(property "MPN" "ERJ2GE0R00X"
				(at 20.32 -20.32 0)
				(effects
					(font
						(size 1.27 1.27)
						(thickness 0.15)
					)
					(justify left bottom)
					(hide yes)
				)
			)
			(property "Manufacturer" "Panasonic"
				(at 20.32 -22.86 0)
				(effects
					(font
						(size 1.27 1.27)
						(thickness 0.15)
					)
					(justify left bottom)
					(hide yes)
				)
			)
			(property "License" "Apache-2.0"
				(at 20.32 -25.4 0)
				(effects
					(font
						(size 1.27 1.27)
						(thickness 0.15)
					)
					(justify left bottom)
					(hide yes)
				)
			)
			(property "Author" "Antmicro"
				(at 20.32 -27.94 0)
				(effects
					(font
						(size 1.27 1.27)
						(thickness 0.15)
					)
					(justify left bottom)
					(hide yes)
				)
			)
			(property "Val" "0R"
				(at 20.32 -7.62 0)
				(effects
					(font
						(size 1.27 1.27)
						(thickness 0.15)
					)
					(justify left bottom)
				)
			)
			(property "Tolerance" "~"
				(at 20.32 -10.16 0)
				(effects
					(font
						(size 1.27 1.27)
					)
					(justify left bottom)
					(hide yes)
				)
			)
			(property "Current" "1A"
				(at 20.32 -30.48 0)
				(effects
					(font
						(size 1.27 1.27)
						(thickness 0.15)
					)
					(justify left bottom)
					(hide yes)
				)
			)
			(symbol "R_0R_0402_0_1"
				(rectangle
					(start 0.635 0.889)
					(end 4.445 -0.889)
					(stroke
						(width 0.254)
						(type default)
					)
					(fill
						(type none)
					)
				)
			)
			(symbol "R_0R_0402_1_1"
				(pin passive line
					(at 0 0 0)
					(length 0.635)
					(name "~"
						(effects
							(font
								(size 1.27 1.27)
							)
						)
					)
					(number "1"
						(effects
							(font
								(size 1.27 1.27)
							)
						)
					)
				)
				(pin passive line
					(at 5.08 0 180)
					(length 0.635)
					(name "~"
						(effects
							(font
								(size 1.27 1.27)
							)
						)
					)
					(number "2"
						(effects
							(font
								(size 1.27 1.27)
							)
						)
					)
				)
			)
		)
	(symbol "antmicroResistors0402:R_100R_0402"
			(pin_numbers
				(hide yes)
			)
			(pin_names
				(hide yes)
			)
			(exclude_from_sim no)
			(in_bom yes)
			(on_board yes)
			(property "Reference" "R"
				(at 20.32 -5.08 0)
				(effects
					(font
						(size 1.27 1.27)
						(thickness 0.15)
					)
					(justify left bottom)
				)
			)
			(property "Value" "R_100R_0402"
				(at 20.32 -12.7 0)
				(effects
					(font
						(size 1.27 1.27)
						(thickness 0.15)
					)
					(justify left bottom)
					(hide yes)
				)
			)
			(property "Footprint" "antmicro-footprints:R_0402_1005Metric"
				(at 20.32 -15.24 0)
				(effects
					(font
						(size 1.27 1.27)
						(thickness 0.15)
					)
					(justify left bottom)
					(hide yes)
				)
			)
			(property "Datasheet" "https://www.bourns.com/docs/product-datasheets/cr.pdf"
				(at 20.32 -17.78 0)
				(effects
					(font
						(size 1.27 1.27)
						(thickness 0.15)
					)
					(justify left bottom)
					(hide yes)
				)
			)
			(property "Description" "100R resistor in 0402 package with 1% tolerance"
				(at 0 0 0)
				(effects
					(font
						(size 1.27 1.27)
					)
					(hide yes)
				)
			)
			(property "MPN" "CR0402-FX-1000GLF"
				(at 20.32 -20.32 0)
				(effects
					(font
						(size 1.27 1.27)
						(thickness 0.15)
					)
					(justify left bottom)
					(hide yes)
				)
			)
			(property "Manufacturer" "Bourns"
				(at 20.32 -22.86 0)
				(effects
					(font
						(size 1.27 1.27)
						(thickness 0.15)
					)
					(justify left bottom)
					(hide yes)
				)
			)
			(property "License" "Apache-2.0"
				(at 20.32 -25.4 0)
				(effects
					(font
						(size 1.27 1.27)
						(thickness 0.15)
					)
					(justify left bottom)
					(hide yes)
				)
			)
			(property "Author" "Antmicro"
				(at 20.32 -27.94 0)
				(effects
					(font
						(size 1.27 1.27)
						(thickness 0.15)
					)
					(justify left bottom)
					(hide yes)
				)
			)
			(property "Val" "100R"
				(at 20.32 -7.62 0)
				(effects
					(font
						(size 1.27 1.27)
						(thickness 0.15)
					)
					(justify left bottom)
				)
			)
			(property "Tolerance" "1%"
				(at 20.32 -10.16 0)
				(effects
					(font
						(size 1.27 1.27)
					)
					(justify left bottom)
					(hide yes)
				)
			)
			(symbol "R_100R_0402_0_1"
				(rectangle
					(start 0.635 0.889)
					(end 4.445 -0.889)
					(stroke
						(width 0.254)
						(type default)
					)
					(fill
						(type none)
					)
				)
			)
			(symbol "R_100R_0402_1_1"
				(pin passive line
					(at 0 0 0)
					(length 0.635)
					(name "~"
						(effects
							(font
								(size 1.27 1.27)
							)
						)
					)
					(number "1"
						(effects
							(font
								(size 1.27 1.27)
							)
						)
					)
				)
				(pin passive line
					(at 5.08 0 180)
					(length 0.635)
					(name "~"
						(effects
							(font
								(size 1.27 1.27)
							)
						)
					)
					(number "2"
						(effects
							(font
								(size 1.27 1.27)
							)
						)
					)
				)
			)
		)
	(symbol "antmicroResistors0402:R_100k_0402"
			(pin_numbers
				(hide yes)
			)
			(pin_names
				(hide yes)
			)
			(exclude_from_sim no)
			(in_bom yes)
			(on_board yes)
			(property "Reference" "R"
				(at 20.32 -5.08 0)
				(effects
					(font
						(size 1.27 1.27)
						(thickness 0.15)
					)
					(justify left bottom)
				)
			)
			(property "Value" "R_100k_0402"
				(at 20.32 -12.7 0)
				(effects
					(font
						(size 1.27 1.27)
						(thickness 0.15)
					)
					(justify left bottom)
					(hide yes)
				)
			)
			(property "Footprint" "antmicro-footprints:R_0402_1005Metric"
				(at 20.32 -15.24 0)
				(effects
					(font
						(size 1.27 1.27)
						(thickness 0.15)
					)
					(justify left bottom)
					(hide yes)
				)
			)
			(property "Datasheet" "https://www.bourns.com/docs/product-datasheets/cr.pdf"
				(at 20.32 -17.78 0)
				(effects
					(font
						(size 1.27 1.27)
						(thickness 0.15)
					)
					(justify left bottom)
					(hide yes)
				)
			)
			(property "Description" "100k resistor in 0402 package with 1% tolerance"
				(at 0 0 0)
				(effects
					(font
						(size 1.27 1.27)
					)
					(hide yes)
				)
			)
			(property "MPN" "CR0402-FX-1003GLF"
				(at 20.32 -20.32 0)
				(effects
					(font
						(size 1.27 1.27)
						(thickness 0.15)
					)
					(justify left bottom)
					(hide yes)
				)
			)
			(property "Manufacturer" "Bourns"
				(at 20.32 -22.86 0)
				(effects
					(font
						(size 1.27 1.27)
						(thickness 0.15)
					)
					(justify left bottom)
					(hide yes)
				)
			)
			(property "License" "Apache-2.0"
				(at 20.32 -25.4 0)
				(effects
					(font
						(size 1.27 1.27)
						(thickness 0.15)
					)
					(justify left bottom)
					(hide yes)
				)
			)
			(property "Author" "Antmicro"
				(at 20.32 -27.94 0)
				(effects
					(font
						(size 1.27 1.27)
						(thickness 0.15)
					)
					(justify left bottom)
					(hide yes)
				)
			)
			(property "Val" "100k"
				(at 20.32 -7.62 0)
				(effects
					(font
						(size 1.27 1.27)
						(thickness 0.15)
					)
					(justify left bottom)
				)
			)
			(property "Tolerance" "1%"
				(at 20.32 -10.16 0)
				(effects
					(font
						(size 1.27 1.27)
					)
					(justify left bottom)
					(hide yes)
				)
			)
			(symbol "R_100k_0402_0_1"
				(rectangle
					(start 0.635 0.889)
					(end 4.445 -0.889)
					(stroke
						(width 0.254)
						(type default)
					)
					(fill
						(type none)
					)
				)
			)
			(symbol "R_100k_0402_1_1"
				(pin passive line
					(at 0 0 0)
					(length 0.635)
					(name "~"
						(effects
							(font
								(size 1.27 1.27)
							)
						)
					)
					(number "1"
						(effects
							(font
								(size 1.27 1.27)
							)
						)
					)
				)
				(pin passive line
					(at 5.08 0 180)
					(length 0.635)
					(name "~"
						(effects
							(font
								(size 1.27 1.27)
							)
						)
					)
					(number "2"
						(effects
							(font
								(size 1.27 1.27)
							)
						)
					)
				)
			)
		)
	(symbol "antmicroResistors0402:R_10R_0402"
			(pin_numbers
				(hide yes)
			)
			(pin_names
				(hide yes)
			)
			(exclude_from_sim no)
			(in_bom yes)
			(on_board yes)
			(property "Reference" "R"
				(at 20.32 -5.08 0)
				(effects
					(font
						(size 1.27 1.27)
						(thickness 0.15)
					)
					(justify left bottom)
				)
			)
			(property "Value" "R_10R_0402"
				(at 20.32 -12.7 0)
				(effects
					(font
						(size 1.27 1.27)
						(thickness 0.15)
					)
					(justify left bottom)
					(hide yes)
				)
			)
			(property "Footprint" "antmicro-footprints:R_0402_1005Metric"
				(at 20.32 -15.24 0)
				(effects
					(font
						(size 1.27 1.27)
						(thickness 0.15)
					)
					(justify left bottom)
					(hide yes)
				)
			)
			(property "Datasheet" "https://www.bourns.com/docs/product-datasheets/cr.pdf"
				(at 20.32 -17.78 0)
				(effects
					(font
						(size 1.27 1.27)
						(thickness 0.15)
					)
					(justify left bottom)
					(hide yes)
				)
			)
			(property "Description" "10R resistor in 0402 package with 1% tolerance"
				(at 0 0 0)
				(effects
					(font
						(size 1.27 1.27)
					)
					(hide yes)
				)
			)
			(property "MPN" "CR0402-FX-10R0GLF"
				(at 20.32 -20.32 0)
				(effects
					(font
						(size 1.27 1.27)
						(thickness 0.15)
					)
					(justify left bottom)
					(hide yes)
				)
			)
			(property "Manufacturer" "Bourns"
				(at 20.32 -22.86 0)
				(effects
					(font
						(size 1.27 1.27)
						(thickness 0.15)
					)
					(justify left bottom)
					(hide yes)
				)
			)
			(property "License" "Apache-2.0"
				(at 20.32 -25.4 0)
				(effects
					(font
						(size 1.27 1.27)
						(thickness 0.15)
					)
					(justify left bottom)
					(hide yes)
				)
			)
			(property "Author" "Antmicro"
				(at 20.32 -27.94 0)
				(effects
					(font
						(size 1.27 1.27)
						(thickness 0.15)
					)
					(justify left bottom)
					(hide yes)
				)
			)
			(property "Val" "10R"
				(at 20.32 -7.62 0)
				(effects
					(font
						(size 1.27 1.27)
						(thickness 0.15)
					)
					(justify left bottom)
				)
			)
			(property "Tolerance" "1%"
				(at 20.32 -10.16 0)
				(effects
					(font
						(size 1.27 1.27)
					)
					(justify left bottom)
					(hide yes)
				)
			)
			(symbol "R_10R_0402_0_1"
				(rectangle
					(start 0.635 0.889)
					(end 4.445 -0.889)
					(stroke
						(width 0.254)
						(type default)
					)
					(fill
						(type none)
					)
				)
			)
			(symbol "R_10R_0402_1_1"
				(pin passive line
					(at 0 0 0)
					(length 0.635)
					(name "~"
						(effects
							(font
								(size 1.27 1.27)
							)
						)
					)
					(number "1"
						(effects
							(font
								(size 1.27 1.27)
							)
						)
					)
				)
				(pin passive line
					(at 5.08 0 180)
					(length 0.635)
					(name "~"
						(effects
							(font
								(size 1.27 1.27)
							)
						)
					)
					(number "2"
						(effects
							(font
								(size 1.27 1.27)
							)
						)
					)
				)
			)
		)
	(symbol "antmicroResistors0402:R_10k2_0402"
			(pin_numbers
				(hide yes)
			)
			(pin_names
				(hide yes)
			)
			(exclude_from_sim no)
			(in_bom yes)
			(on_board yes)
			(property "Reference" "R"
				(at 20.32 -5.08 0)
				(effects
					(font
						(size 1.27 1.27)
						(thickness 0.15)
					)
					(justify left bottom)
				)
			)
			(property "Value" "R_10k2_0402"
				(at 20.32 -12.7 0)
				(effects
					(font
						(size 1.27 1.27)
						(thickness 0.15)
					)
					(justify left bottom)
					(hide yes)
				)
			)
			(property "Footprint" "antmicro-footprints:R_0402_1005Metric"
				(at 20.32 -15.24 0)
				(effects
					(font
						(size 1.27 1.27)
						(thickness 0.15)
					)
					(justify left bottom)
					(hide yes)
				)
			)
			(property "Datasheet" "https://www.bourns.com/docs/product-datasheets/cr.pdf"
				(at 20.32 -17.78 0)
				(effects
					(font
						(size 1.27 1.27)
						(thickness 0.15)
					)
					(justify left bottom)
					(hide yes)
				)
			)
			(property "Description" "10k2 resistor in 0402 package with 1% tolerance"
				(at 0 0 0)
				(effects
					(font
						(size 1.27 1.27)
					)
					(hide yes)
				)
			)
			(property "MPN" "CR0402-FX-1022GLF"
				(at 20.32 -20.32 0)
				(effects
					(font
						(size 1.27 1.27)
						(thickness 0.15)
					)
					(justify left bottom)
					(hide yes)
				)
			)
			(property "Manufacturer" "Bourns"
				(at 20.32 -22.86 0)
				(effects
					(font
						(size 1.27 1.27)
						(thickness 0.15)
					)
					(justify left bottom)
					(hide yes)
				)
			)
			(property "License" "Apache-2.0"
				(at 20.32 -25.4 0)
				(effects
					(font
						(size 1.27 1.27)
						(thickness 0.15)
					)
					(justify left bottom)
					(hide yes)
				)
			)
			(property "Author" "Antmicro"
				(at 20.32 -27.94 0)
				(effects
					(font
						(size 1.27 1.27)
						(thickness 0.15)
					)
					(justify left bottom)
					(hide yes)
				)
			)
			(property "Val" "10k2"
				(at 20.32 -7.62 0)
				(effects
					(font
						(size 1.27 1.27)
						(thickness 0.15)
					)
					(justify left bottom)
				)
			)
			(property "Tolerance" "1%"
				(at 20.32 -10.16 0)
				(effects
					(font
						(size 1.27 1.27)
					)
					(justify left bottom)
					(hide yes)
				)
			)
			(symbol "R_10k2_0402_0_1"
				(rectangle
					(start 0.635 0.889)
					(end 4.445 -0.889)
					(stroke
						(width 0.254)
						(type default)
					)
					(fill
						(type none)
					)
				)
			)
			(symbol "R_10k2_0402_1_1"
				(pin passive line
					(at 0 0 0)
					(length 0.635)
					(name "~"
						(effects
							(font
								(size 1.27 1.27)
							)
						)
					)
					(number "1"
						(effects
							(font
								(size 1.27 1.27)
							)
						)
					)
				)
				(pin passive line
					(at 5.08 0 180)
					(length 0.635)
					(name "~"
						(effects
							(font
								(size 1.27 1.27)
							)
						)
					)
					(number "2"
						(effects
							(font
								(size 1.27 1.27)
							)
						)
					)
				)
			)
		)
	(symbol "antmicroResistors0402:R_10k_0402"
			(pin_numbers
				(hide yes)
			)
			(pin_names
				(hide yes)
			)
			(exclude_from_sim no)
			(in_bom yes)
			(on_board yes)
			(property "Reference" "R"
				(at 20.32 -5.08 0)
				(effects
					(font
						(size 1.27 1.27)
						(thickness 0.15)
					)
					(justify left bottom)
				)
			)
			(property "Value" "R_10k_0402"
				(at 20.32 -12.7 0)
				(effects
					(font
						(size 1.27 1.27)
						(thickness 0.15)
					)
					(justify left bottom)
					(hide yes)
				)
			)
			(property "Footprint" "antmicro-footprints:R_0402_1005Metric"
				(at 20.32 -15.24 0)
				(effects
					(font
						(size 1.27 1.27)
						(thickness 0.15)
					)
					(justify left bottom)
					(hide yes)
				)
			)
			(property "Datasheet" "https://www.bourns.com/docs/product-datasheets/cr.pdf"
				(at 20.32 -17.78 0)
				(effects
					(font
						(size 1.27 1.27)
						(thickness 0.15)
					)
					(justify left bottom)
					(hide yes)
				)
			)
			(property "Description" "10k resistor in 0402 package with 1% tolerance"
				(at 0 0 0)
				(effects
					(font
						(size 1.27 1.27)
					)
					(hide yes)
				)
			)
			(property "MPN" "CR0402-FX-1002GLF"
				(at 20.32 -20.32 0)
				(effects
					(font
						(size 1.27 1.27)
						(thickness 0.15)
					)
					(justify left bottom)
					(hide yes)
				)
			)
			(property "Manufacturer" "Bourns"
				(at 20.32 -22.86 0)
				(effects
					(font
						(size 1.27 1.27)
						(thickness 0.15)
					)
					(justify left bottom)
					(hide yes)
				)
			)
			(property "License" "Apache-2.0"
				(at 20.32 -25.4 0)
				(effects
					(font
						(size 1.27 1.27)
						(thickness 0.15)
					)
					(justify left bottom)
					(hide yes)
				)
			)
			(property "Author" "Antmicro"
				(at 20.32 -27.94 0)
				(effects
					(font
						(size 1.27 1.27)
						(thickness 0.15)
					)
					(justify left bottom)
					(hide yes)
				)
			)
			(property "Val" "10k"
				(at 20.32 -7.62 0)
				(effects
					(font
						(size 1.27 1.27)
						(thickness 0.15)
					)
					(justify left bottom)
				)
			)
			(property "Tolerance" "1%"
				(at 20.32 -10.16 0)
				(effects
					(font
						(size 1.27 1.27)
					)
					(justify left bottom)
					(hide yes)
				)
			)
			(symbol "R_10k_0402_0_1"
				(rectangle
					(start 0.635 0.889)
					(end 4.445 -0.889)
					(stroke
						(width 0.254)
						(type default)
					)
					(fill
						(type none)
					)
				)
			)
			(symbol "R_10k_0402_1_1"
				(pin passive line
					(at 0 0 0)
					(length 0.635)
					(name "~"
						(effects
							(font
								(size 1.27 1.27)
							)
						)
					)
					(number "1"
						(effects
							(font
								(size 1.27 1.27)
							)
						)
					)
				)
				(pin passive line
					(at 5.08 0 180)
					(length 0.635)
					(name "~"
						(effects
							(font
								(size 1.27 1.27)
							)
						)
					)
					(number "2"
						(effects
							(font
								(size 1.27 1.27)
							)
						)
					)
				)
			)
		)
	(symbol "antmicroResistors0402:R_12k1_0402"
			(pin_numbers
				(hide yes)
			)
			(pin_names
				(hide yes)
			)
			(exclude_from_sim no)
			(in_bom yes)
			(on_board yes)
			(property "Reference" "R"
				(at 20.32 -5.08 0)
				(effects
					(font
						(size 1.27 1.27)
						(thickness 0.15)
					)
					(justify left bottom)
				)
			)
			(property "Value" "R_12k1_0402"
				(at 20.32 -12.7 0)
				(effects
					(font
						(size 1.27 1.27)
						(thickness 0.15)
					)
					(justify left bottom)
					(hide yes)
				)
			)
			(property "Footprint" "antmicro-footprints:R_0402_1005Metric"
				(at 20.32 -15.24 0)
				(effects
					(font
						(size 1.27 1.27)
						(thickness 0.15)
					)
					(justify left bottom)
					(hide yes)
				)
			)
			(property "Datasheet" "https://www.bourns.com/docs/product-datasheets/cr.pdf"
				(at 20.32 -17.78 0)
				(effects
					(font
						(size 1.27 1.27)
						(thickness 0.15)
					)
					(justify left bottom)
					(hide yes)
				)
			)
			(property "Description" "12k1 resistor in 0402 package with 1% tolerance"
				(at 0 0 0)
				(effects
					(font
						(size 1.27 1.27)
					)
					(hide yes)
				)
			)
			(property "MPN" "CR0402-FX-1212GLF"
				(at 20.32 -20.32 0)
				(effects
					(font
						(size 1.27 1.27)
						(thickness 0.15)
					)
					(justify left bottom)
					(hide yes)
				)
			)
			(property "Manufacturer" "Bourns"
				(at 20.32 -22.86 0)
				(effects
					(font
						(size 1.27 1.27)
						(thickness 0.15)
					)
					(justify left bottom)
					(hide yes)
				)
			)
			(property "License" "Apache-2.0"
				(at 20.32 -25.4 0)
				(effects
					(font
						(size 1.27 1.27)
						(thickness 0.15)
					)
					(justify left bottom)
					(hide yes)
				)
			)
			(property "Author" "Antmicro"
				(at 20.32 -27.94 0)
				(effects
					(font
						(size 1.27 1.27)
						(thickness 0.15)
					)
					(justify left bottom)
					(hide yes)
				)
			)
			(property "Val" "12k1"
				(at 20.32 -7.62 0)
				(effects
					(font
						(size 1.27 1.27)
						(thickness 0.15)
					)
					(justify left bottom)
				)
			)
			(property "Tolerance" "1%"
				(at 20.32 -10.16 0)
				(effects
					(font
						(size 1.27 1.27)
					)
					(justify left bottom)
					(hide yes)
				)
			)
			(symbol "R_12k1_0402_0_1"
				(rectangle
					(start 0.635 0.889)
					(end 4.445 -0.889)
					(stroke
						(width 0.254)
						(type default)
					)
					(fill
						(type none)
					)
				)
			)
			(symbol "R_12k1_0402_1_1"
				(pin passive line
					(at 0 0 0)
					(length 0.635)
					(name "~"
						(effects
							(font
								(size 1.27 1.27)
							)
						)
					)
					(number "1"
						(effects
							(font
								(size 1.27 1.27)
							)
						)
					)
				)
				(pin passive line
					(at 5.08 0 180)
					(length 0.635)
					(name "~"
						(effects
							(font
								(size 1.27 1.27)
							)
						)
					)
					(number "2"
						(effects
							(font
								(size 1.27 1.27)
							)
						)
					)
				)
			)
		)
	(symbol "antmicroResistors0402:R_12k_0402"
			(pin_numbers
				(hide yes)
			)
			(pin_names
				(hide yes)
			)
			(exclude_from_sim no)
			(in_bom yes)
			(on_board yes)
			(property "Reference" "R"
				(at 20.32 -5.08 0)
				(effects
					(font
						(size 1.27 1.27)
						(thickness 0.15)
					)
					(justify left bottom)
				)
			)
			(property "Value" "R_12k_0402"
				(at 20.32 -12.7 0)
				(effects
					(font
						(size 1.27 1.27)
						(thickness 0.15)
					)
					(justify left bottom)
					(hide yes)
				)
			)
			(property "Footprint" "antmicro-footprints:R_0402_1005Metric"
				(at 20.32 -15.24 0)
				(effects
					(font
						(size 1.27 1.27)
						(thickness 0.15)
					)
					(justify left bottom)
					(hide yes)
				)
			)
			(property "Datasheet" "https://www.bourns.com/docs/product-datasheets/cr.pdf"
				(at 20.32 -17.78 0)
				(effects
					(font
						(size 1.27 1.27)
						(thickness 0.15)
					)
					(justify left bottom)
					(hide yes)
				)
			)
			(property "Description" "12k resistor in 0402 package with 1% tolerance"
				(at 0 0 0)
				(effects
					(font
						(size 1.27 1.27)
					)
					(hide yes)
				)
			)
			(property "MPN" "CR0402-FX-1202GLF"
				(at 20.32 -20.32 0)
				(effects
					(font
						(size 1.27 1.27)
						(thickness 0.15)
					)
					(justify left bottom)
					(hide yes)
				)
			)
			(property "Manufacturer" "Bourns"
				(at 20.32 -22.86 0)
				(effects
					(font
						(size 1.27 1.27)
						(thickness 0.15)
					)
					(justify left bottom)
					(hide yes)
				)
			)
			(property "License" "Apache-2.0"
				(at 20.32 -25.4 0)
				(effects
					(font
						(size 1.27 1.27)
						(thickness 0.15)
					)
					(justify left bottom)
					(hide yes)
				)
			)
			(property "Author" "Antmicro"
				(at 20.32 -27.94 0)
				(effects
					(font
						(size 1.27 1.27)
						(thickness 0.15)
					)
					(justify left bottom)
					(hide yes)
				)
			)
			(property "Val" "12k"
				(at 20.32 -7.62 0)
				(effects
					(font
						(size 1.27 1.27)
						(thickness 0.15)
					)
					(justify left bottom)
				)
			)
			(property "Tolerance" "1%"
				(at 20.32 -10.16 0)
				(effects
					(font
						(size 1.27 1.27)
					)
					(justify left bottom)
					(hide yes)
				)
			)
			(symbol "R_12k_0402_0_1"
				(rectangle
					(start 0.635 0.889)
					(end 4.445 -0.889)
					(stroke
						(width 0.254)
						(type default)
					)
					(fill
						(type none)
					)
				)
			)
			(symbol "R_12k_0402_1_1"
				(pin passive line
					(at 0 0 0)
					(length 0.635)
					(name "~"
						(effects
							(font
								(size 1.27 1.27)
							)
						)
					)
					(number "1"
						(effects
							(font
								(size 1.27 1.27)
							)
						)
					)
				)
				(pin passive line
					(at 5.08 0 180)
					(length 0.635)
					(name "~"
						(effects
							(font
								(size 1.27 1.27)
							)
						)
					)
					(number "2"
						(effects
							(font
								(size 1.27 1.27)
							)
						)
					)
				)
			)
		)
	(symbol "antmicroResistors0402:R_16k9_0402"
			(pin_numbers
				(hide yes)
			)
			(pin_names
				(hide yes)
			)
			(exclude_from_sim no)
			(in_bom yes)
			(on_board yes)
			(property "Reference" "R"
				(at 20.32 -5.08 0)
				(effects
					(font
						(size 1.27 1.27)
						(thickness 0.15)
					)
					(justify left bottom)
				)
			)
			(property "Value" "R_16k9_0402"
				(at 20.32 -12.7 0)
				(effects
					(font
						(size 1.27 1.27)
						(thickness 0.15)
					)
					(justify left bottom)
					(hide yes)
				)
			)
			(property "Footprint" "antmicro-footprints:R_0402_1005Metric"
				(at 20.32 -15.24 0)
				(effects
					(font
						(size 1.27 1.27)
						(thickness 0.15)
					)
					(justify left bottom)
					(hide yes)
				)
			)
			(property "Datasheet" "https://www.bourns.com/docs/product-datasheets/cr.pdf"
				(at 20.32 -17.78 0)
				(effects
					(font
						(size 1.27 1.27)
						(thickness 0.15)
					)
					(justify left bottom)
					(hide yes)
				)
			)
			(property "Description" "16k9 resistor in 0402 package with 1% tolerance"
				(at 0 0 0)
				(effects
					(font
						(size 1.27 1.27)
					)
					(hide yes)
				)
			)
			(property "MPN" "CR0402-FX-1692GLF"
				(at 20.32 -20.32 0)
				(effects
					(font
						(size 1.27 1.27)
						(thickness 0.15)
					)
					(justify left bottom)
					(hide yes)
				)
			)
			(property "Manufacturer" "Bourns"
				(at 20.32 -22.86 0)
				(effects
					(font
						(size 1.27 1.27)
						(thickness 0.15)
					)
					(justify left bottom)
					(hide yes)
				)
			)
			(property "License" "Apache-2.0"
				(at 20.32 -25.4 0)
				(effects
					(font
						(size 1.27 1.27)
						(thickness 0.15)
					)
					(justify left bottom)
					(hide yes)
				)
			)
			(property "Author" "Antmicro"
				(at 20.32 -27.94 0)
				(effects
					(font
						(size 1.27 1.27)
						(thickness 0.15)
					)
					(justify left bottom)
					(hide yes)
				)
			)
			(property "Val" "16k9"
				(at 20.32 -7.62 0)
				(effects
					(font
						(size 1.27 1.27)
						(thickness 0.15)
					)
					(justify left bottom)
				)
			)
			(property "Tolerance" "1%"
				(at 20.32 -10.16 0)
				(effects
					(font
						(size 1.27 1.27)
					)
					(justify left bottom)
					(hide yes)
				)
			)
			(symbol "R_16k9_0402_0_1"
				(rectangle
					(start 0.635 0.889)
					(end 4.445 -0.889)
					(stroke
						(width 0.254)
						(type default)
					)
					(fill
						(type none)
					)
				)
			)
			(symbol "R_16k9_0402_1_1"
				(pin passive line
					(at 0 0 0)
					(length 0.635)
					(name "~"
						(effects
							(font
								(size 1.27 1.27)
							)
						)
					)
					(number "1"
						(effects
							(font
								(size 1.27 1.27)
							)
						)
					)
				)
				(pin passive line
					(at 5.08 0 180)
					(length 0.635)
					(name "~"
						(effects
							(font
								(size 1.27 1.27)
							)
						)
					)
					(number "2"
						(effects
							(font
								(size 1.27 1.27)
							)
						)
					)
				)
			)
		)
	(symbol "antmicroResistors0402:R_1M8_0402"
			(pin_numbers
				(hide yes)
			)
			(pin_names
				(hide yes)
			)
			(exclude_from_sim no)
			(in_bom yes)
			(on_board yes)
			(property "Reference" "R"
				(at 20.32 -5.08 0)
				(effects
					(font
						(size 1.27 1.27)
						(thickness 0.15)
					)
					(justify left bottom)
				)
			)
			(property "Value" "R_1M8_0402"
				(at 20.32 -12.7 0)
				(effects
					(font
						(size 1.27 1.27)
						(thickness 0.15)
					)
					(justify left bottom)
					(hide yes)
				)
			)
			(property "Footprint" "antmicro-footprints:R_0402_1005Metric"
				(at 20.32 -15.24 0)
				(effects
					(font
						(size 1.27 1.27)
						(thickness 0.15)
					)
					(justify left bottom)
					(hide yes)
				)
			)
			(property "Datasheet" "https://www.bourns.com/docs/product-datasheets/cr.pdf"
				(at 20.32 -17.78 0)
				(effects
					(font
						(size 1.27 1.27)
						(thickness 0.15)
					)
					(justify left bottom)
					(hide yes)
				)
			)
			(property "Description" "1M8 resistor in 0402 package with 1% tolerance"
				(at 0 0 0)
				(effects
					(font
						(size 1.27 1.27)
					)
					(hide yes)
				)
			)
			(property "MPN" "CR0402-FX-1804GLF"
				(at 20.32 -20.32 0)
				(effects
					(font
						(size 1.27 1.27)
						(thickness 0.15)
					)
					(justify left bottom)
					(hide yes)
				)
			)
			(property "Manufacturer" "Bourns"
				(at 20.32 -22.86 0)
				(effects
					(font
						(size 1.27 1.27)
						(thickness 0.15)
					)
					(justify left bottom)
					(hide yes)
				)
			)
			(property "License" "Apache-2.0"
				(at 20.32 -25.4 0)
				(effects
					(font
						(size 1.27 1.27)
						(thickness 0.15)
					)
					(justify left bottom)
					(hide yes)
				)
			)
			(property "Author" "Antmicro"
				(at 20.32 -27.94 0)
				(effects
					(font
						(size 1.27 1.27)
						(thickness 0.15)
					)
					(justify left bottom)
					(hide yes)
				)
			)
			(property "Val" "1M8"
				(at 20.32 -7.62 0)
				(effects
					(font
						(size 1.27 1.27)
						(thickness 0.15)
					)
					(justify left bottom)
				)
			)
			(property "Tolerance" "1%"
				(at 20.32 -10.16 0)
				(effects
					(font
						(size 1.27 1.27)
					)
					(justify left bottom)
					(hide yes)
				)
			)
			(symbol "R_1M8_0402_0_1"
				(rectangle
					(start 0.635 0.889)
					(end 4.445 -0.889)
					(stroke
						(width 0.254)
						(type default)
					)
					(fill
						(type none)
					)
				)
			)
			(symbol "R_1M8_0402_1_1"
				(pin passive line
					(at 0 0 0)
					(length 0.635)
					(name "~"
						(effects
							(font
								(size 1.27 1.27)
							)
						)
					)
					(number "1"
						(effects
							(font
								(size 1.27 1.27)
							)
						)
					)
				)
				(pin passive line
					(at 5.08 0 180)
					(length 0.635)
					(name "~"
						(effects
							(font
								(size 1.27 1.27)
							)
						)
					)
					(number "2"
						(effects
							(font
								(size 1.27 1.27)
							)
						)
					)
				)
			)
		)
	(symbol "antmicroResistors0402:R_1k_0402"
			(pin_numbers
				(hide yes)
			)
			(pin_names
				(hide yes)
			)
			(exclude_from_sim no)
			(in_bom yes)
			(on_board yes)
			(property "Reference" "R"
				(at 20.32 -5.08 0)
				(effects
					(font
						(size 1.27 1.27)
						(thickness 0.15)
					)
					(justify left bottom)
				)
			)
			(property "Value" "R_1k_0402"
				(at 20.32 -12.7 0)
				(effects
					(font
						(size 1.27 1.27)
						(thickness 0.15)
					)
					(justify left bottom)
					(hide yes)
				)
			)
			(property "Footprint" "antmicro-footprints:R_0402_1005Metric"
				(at 20.32 -15.24 0)
				(effects
					(font
						(size 1.27 1.27)
						(thickness 0.15)
					)
					(justify left bottom)
					(hide yes)
				)
			)
			(property "Datasheet" "https://www.bourns.com/docs/product-datasheets/cr.pdf"
				(at 20.32 -17.78 0)
				(effects
					(font
						(size 1.27 1.27)
						(thickness 0.15)
					)
					(justify left bottom)
					(hide yes)
				)
			)
			(property "Description" "1k resistor in 0402 package with 1% tolerance"
				(at 0 0 0)
				(effects
					(font
						(size 1.27 1.27)
					)
					(hide yes)
				)
			)
			(property "MPN" "CR0402-FX-1001GLF"
				(at 20.32 -20.32 0)
				(effects
					(font
						(size 1.27 1.27)
						(thickness 0.15)
					)
					(justify left bottom)
					(hide yes)
				)
			)
			(property "Manufacturer" "Bourns"
				(at 20.32 -22.86 0)
				(effects
					(font
						(size 1.27 1.27)
						(thickness 0.15)
					)
					(justify left bottom)
					(hide yes)
				)
			)
			(property "License" "Apache-2.0"
				(at 20.32 -25.4 0)
				(effects
					(font
						(size 1.27 1.27)
						(thickness 0.15)
					)
					(justify left bottom)
					(hide yes)
				)
			)
			(property "Author" "Antmicro"
				(at 20.32 -27.94 0)
				(effects
					(font
						(size 1.27 1.27)
						(thickness 0.15)
					)
					(justify left bottom)
					(hide yes)
				)
			)
			(property "Val" "1k"
				(at 20.32 -7.62 0)
				(effects
					(font
						(size 1.27 1.27)
						(thickness 0.15)
					)
					(justify left bottom)
				)
			)
			(property "Tolerance" "1%"
				(at 20.32 -10.16 0)
				(effects
					(font
						(size 1.27 1.27)
					)
					(justify left bottom)
					(hide yes)
				)
			)
			(symbol "R_1k_0402_0_1"
				(rectangle
					(start 0.635 0.889)
					(end 4.445 -0.889)
					(stroke
						(width 0.254)
						(type default)
					)
					(fill
						(type none)
					)
				)
			)
			(symbol "R_1k_0402_1_1"
				(pin passive line
					(at 0 0 0)
					(length 0.635)
					(name "~"
						(effects
							(font
								(size 1.27 1.27)
							)
						)
					)
					(number "1"
						(effects
							(font
								(size 1.27 1.27)
							)
						)
					)
				)
				(pin passive line
					(at 5.08 0 180)
					(length 0.635)
					(name "~"
						(effects
							(font
								(size 1.27 1.27)
							)
						)
					)
					(number "2"
						(effects
							(font
								(size 1.27 1.27)
							)
						)
					)
				)
			)
		)
	(symbol "antmicroResistors0402:R_20k_0402"
			(pin_numbers
				(hide yes)
			)
			(pin_names
				(hide yes)
			)
			(exclude_from_sim no)
			(in_bom yes)
			(on_board yes)
			(property "Reference" "R"
				(at 20.32 -5.08 0)
				(effects
					(font
						(size 1.27 1.27)
						(thickness 0.15)
					)
					(justify left bottom)
				)
			)
			(property "Value" "R_20k_0402"
				(at 20.32 -12.7 0)
				(effects
					(font
						(size 1.27 1.27)
						(thickness 0.15)
					)
					(justify left bottom)
					(hide yes)
				)
			)
			(property "Footprint" "antmicro-footprints:R_0402_1005Metric"
				(at 20.32 -15.24 0)
				(effects
					(font
						(size 1.27 1.27)
						(thickness 0.15)
					)
					(justify left bottom)
					(hide yes)
				)
			)
			(property "Datasheet" "https://www.bourns.com/docs/product-datasheets/cr.pdf"
				(at 20.32 -17.78 0)
				(effects
					(font
						(size 1.27 1.27)
						(thickness 0.15)
					)
					(justify left bottom)
					(hide yes)
				)
			)
			(property "Description" "20k resistor in 0402 package with 1% tolerance"
				(at 0 0 0)
				(effects
					(font
						(size 1.27 1.27)
					)
					(hide yes)
				)
			)
			(property "MPN" "CR0402-FX-2002GLF"
				(at 20.32 -20.32 0)
				(effects
					(font
						(size 1.27 1.27)
						(thickness 0.15)
					)
					(justify left bottom)
					(hide yes)
				)
			)
			(property "Manufacturer" "Bourns"
				(at 20.32 -22.86 0)
				(effects
					(font
						(size 1.27 1.27)
						(thickness 0.15)
					)
					(justify left bottom)
					(hide yes)
				)
			)
			(property "License" "Apache-2.0"
				(at 20.32 -25.4 0)
				(effects
					(font
						(size 1.27 1.27)
						(thickness 0.15)
					)
					(justify left bottom)
					(hide yes)
				)
			)
			(property "Author" "Antmicro"
				(at 20.32 -27.94 0)
				(effects
					(font
						(size 1.27 1.27)
						(thickness 0.15)
					)
					(justify left bottom)
					(hide yes)
				)
			)
			(property "Val" "20k"
				(at 20.32 -7.62 0)
				(effects
					(font
						(size 1.27 1.27)
						(thickness 0.15)
					)
					(justify left bottom)
				)
			)
			(property "Tolerance" "1%"
				(at 20.32 -10.16 0)
				(effects
					(font
						(size 1.27 1.27)
					)
					(justify left bottom)
					(hide yes)
				)
			)
			(symbol "R_20k_0402_0_1"
				(rectangle
					(start 0.635 0.889)
					(end 4.445 -0.889)
					(stroke
						(width 0.254)
						(type default)
					)
					(fill
						(type none)
					)
				)
			)
			(symbol "R_20k_0402_1_1"
				(pin passive line
					(at 0 0 0)
					(length 0.635)
					(name "~"
						(effects
							(font
								(size 1.27 1.27)
							)
						)
					)
					(number "1"
						(effects
							(font
								(size 1.27 1.27)
							)
						)
					)
				)
				(pin passive line
					(at 5.08 0 180)
					(length 0.635)
					(name "~"
						(effects
							(font
								(size 1.27 1.27)
							)
						)
					)
					(number "2"
						(effects
							(font
								(size 1.27 1.27)
							)
						)
					)
				)
			)
		)
	(symbol "antmicroResistors0402:R_220R_0402"
			(pin_numbers
				(hide yes)
			)
			(pin_names
				(hide yes)
			)
			(exclude_from_sim no)
			(in_bom yes)
			(on_board yes)
			(property "Reference" "R"
				(at 20.32 -5.08 0)
				(effects
					(font
						(size 1.27 1.27)
						(thickness 0.15)
					)
					(justify left bottom)
				)
			)
			(property "Value" "R_220R_0402"
				(at 20.32 -12.7 0)
				(effects
					(font
						(size 1.27 1.27)
						(thickness 0.15)
					)
					(justify left bottom)
					(hide yes)
				)
			)
			(property "Footprint" "antmicro-footprints:R_0402_1005Metric"
				(at 20.32 -15.24 0)
				(effects
					(font
						(size 1.27 1.27)
						(thickness 0.15)
					)
					(justify left bottom)
					(hide yes)
				)
			)
			(property "Datasheet" "https://www.bourns.com/docs/product-datasheets/cr.pdf"
				(at 20.32 -17.78 0)
				(effects
					(font
						(size 1.27 1.27)
						(thickness 0.15)
					)
					(justify left bottom)
					(hide yes)
				)
			)
			(property "Description" "220R resistor in 0402 package with 1% tolerance"
				(at 0 0 0)
				(effects
					(font
						(size 1.27 1.27)
					)
					(hide yes)
				)
			)
			(property "MPN" "CR0402-FX-2200GLF"
				(at 20.32 -20.32 0)
				(effects
					(font
						(size 1.27 1.27)
						(thickness 0.15)
					)
					(justify left bottom)
					(hide yes)
				)
			)
			(property "Manufacturer" "Bourns"
				(at 20.32 -22.86 0)
				(effects
					(font
						(size 1.27 1.27)
						(thickness 0.15)
					)
					(justify left bottom)
					(hide yes)
				)
			)
			(property "License" "Apache-2.0"
				(at 20.32 -25.4 0)
				(effects
					(font
						(size 1.27 1.27)
						(thickness 0.15)
					)
					(justify left bottom)
					(hide yes)
				)
			)
			(property "Author" "Antmicro"
				(at 20.32 -27.94 0)
				(effects
					(font
						(size 1.27 1.27)
						(thickness 0.15)
					)
					(justify left bottom)
					(hide yes)
				)
			)
			(property "Val" "220R"
				(at 20.32 -7.62 0)
				(effects
					(font
						(size 1.27 1.27)
						(thickness 0.15)
					)
					(justify left bottom)
				)
			)
			(property "Tolerance" "1%"
				(at 20.32 -10.16 0)
				(effects
					(font
						(size 1.27 1.27)
					)
					(justify left bottom)
					(hide yes)
				)
			)
			(symbol "R_220R_0402_0_1"
				(rectangle
					(start 0.635 0.889)
					(end 4.445 -0.889)
					(stroke
						(width 0.254)
						(type default)
					)
					(fill
						(type none)
					)
				)
			)
			(symbol "R_220R_0402_1_1"
				(pin passive line
					(at 0 0 0)
					(length 0.635)
					(name "~"
						(effects
							(font
								(size 1.27 1.27)
							)
						)
					)
					(number "1"
						(effects
							(font
								(size 1.27 1.27)
							)
						)
					)
				)
				(pin passive line
					(at 5.08 0 180)
					(length 0.635)
					(name "~"
						(effects
							(font
								(size 1.27 1.27)
							)
						)
					)
					(number "2"
						(effects
							(font
								(size 1.27 1.27)
							)
						)
					)
				)
			)
		)
	(symbol "antmicroResistors0402:R_22R_0402"
			(pin_numbers
				(hide yes)
			)
			(pin_names
				(hide yes)
			)
			(exclude_from_sim no)
			(in_bom yes)
			(on_board yes)
			(property "Reference" "R"
				(at 20.32 -5.08 0)
				(effects
					(font
						(size 1.27 1.27)
						(thickness 0.15)
					)
					(justify left bottom)
				)
			)
			(property "Value" "R_22R_0402"
				(at 20.32 -12.7 0)
				(effects
					(font
						(size 1.27 1.27)
						(thickness 0.15)
					)
					(justify left bottom)
					(hide yes)
				)
			)
			(property "Footprint" "antmicro-footprints:R_0402_1005Metric"
				(at 20.32 -15.24 0)
				(effects
					(font
						(size 1.27 1.27)
						(thickness 0.15)
					)
					(justify left bottom)
					(hide yes)
				)
			)
			(property "Datasheet" "https://www.bourns.com/docs/product-datasheets/cr.pdf"
				(at 20.32 -17.78 0)
				(effects
					(font
						(size 1.27 1.27)
						(thickness 0.15)
					)
					(justify left bottom)
					(hide yes)
				)
			)
			(property "Description" "22R resistor in 0402 package with 1% tolerance"
				(at 0 0 0)
				(effects
					(font
						(size 1.27 1.27)
					)
					(hide yes)
				)
			)
			(property "MPN" "CR0402-FX-22R0GLF"
				(at 20.32 -20.32 0)
				(effects
					(font
						(size 1.27 1.27)
						(thickness 0.15)
					)
					(justify left bottom)
					(hide yes)
				)
			)
			(property "Manufacturer" "Bourns"
				(at 20.32 -22.86 0)
				(effects
					(font
						(size 1.27 1.27)
						(thickness 0.15)
					)
					(justify left bottom)
					(hide yes)
				)
			)
			(property "License" "Apache-2.0"
				(at 20.32 -25.4 0)
				(effects
					(font
						(size 1.27 1.27)
						(thickness 0.15)
					)
					(justify left bottom)
					(hide yes)
				)
			)
			(property "Author" "Antmicro"
				(at 20.32 -27.94 0)
				(effects
					(font
						(size 1.27 1.27)
						(thickness 0.15)
					)
					(justify left bottom)
					(hide yes)
				)
			)
			(property "Val" "22R"
				(at 20.32 -7.62 0)
				(effects
					(font
						(size 1.27 1.27)
						(thickness 0.15)
					)
					(justify left bottom)
				)
			)
			(property "Tolerance" "1%"
				(at 20.32 -10.16 0)
				(effects
					(font
						(size 1.27 1.27)
					)
					(justify left bottom)
					(hide yes)
				)
			)
			(symbol "R_22R_0402_0_1"
				(rectangle
					(start 0.635 0.889)
					(end 4.445 -0.889)
					(stroke
						(width 0.254)
						(type default)
					)
					(fill
						(type none)
					)
				)
			)
			(symbol "R_22R_0402_1_1"
				(pin passive line
					(at 0 0 0)
					(length 0.635)
					(name "~"
						(effects
							(font
								(size 1.27 1.27)
							)
						)
					)
					(number "1"
						(effects
							(font
								(size 1.27 1.27)
							)
						)
					)
				)
				(pin passive line
					(at 5.08 0 180)
					(length 0.635)
					(name "~"
						(effects
							(font
								(size 1.27 1.27)
							)
						)
					)
					(number "2"
						(effects
							(font
								(size 1.27 1.27)
							)
						)
					)
				)
			)
		)
	(symbol "antmicroResistors0402:R_243k_0402"
			(pin_numbers
				(hide yes)
			)
			(pin_names
				(hide yes)
			)
			(exclude_from_sim no)
			(in_bom yes)
			(on_board yes)
			(property "Reference" "R"
				(at 20.32 -5.08 0)
				(effects
					(font
						(size 1.27 1.27)
						(thickness 0.15)
					)
					(justify left bottom)
				)
			)
			(property "Value" "R_243k_0402"
				(at 20.32 -12.7 0)
				(effects
					(font
						(size 1.27 1.27)
						(thickness 0.15)
					)
					(justify left bottom)
					(hide yes)
				)
			)
			(property "Footprint" "antmicro-footprints:R_0402_1005Metric"
				(at 20.32 -15.24 0)
				(effects
					(font
						(size 1.27 1.27)
						(thickness 0.15)
					)
					(justify left bottom)
					(hide yes)
				)
			)
			(property "Datasheet" "https://www.bourns.com/docs/product-datasheets/cr.pdf"
				(at 20.32 -17.78 0)
				(effects
					(font
						(size 1.27 1.27)
						(thickness 0.15)
					)
					(justify left bottom)
					(hide yes)
				)
			)
			(property "Description" "243k resistor in 0402 package with 1% tolerance"
				(at 0 0 0)
				(effects
					(font
						(size 1.27 1.27)
					)
					(hide yes)
				)
			)
			(property "MPN" "CR0402-FX-2433GLF"
				(at 20.32 -20.32 0)
				(effects
					(font
						(size 1.27 1.27)
						(thickness 0.15)
					)
					(justify left bottom)
					(hide yes)
				)
			)
			(property "Manufacturer" "Bourns"
				(at 20.32 -22.86 0)
				(effects
					(font
						(size 1.27 1.27)
						(thickness 0.15)
					)
					(justify left bottom)
					(hide yes)
				)
			)
			(property "License" "Apache-2.0"
				(at 20.32 -25.4 0)
				(effects
					(font
						(size 1.27 1.27)
						(thickness 0.15)
					)
					(justify left bottom)
					(hide yes)
				)
			)
			(property "Author" "Antmicro"
				(at 20.32 -27.94 0)
				(effects
					(font
						(size 1.27 1.27)
						(thickness 0.15)
					)
					(justify left bottom)
					(hide yes)
				)
			)
			(property "Val" "243k"
				(at 20.32 -7.62 0)
				(effects
					(font
						(size 1.27 1.27)
						(thickness 0.15)
					)
					(justify left bottom)
				)
			)
			(property "Tolerance" "1%"
				(at 20.32 -10.16 0)
				(effects
					(font
						(size 1.27 1.27)
					)
					(justify left bottom)
					(hide yes)
				)
			)
			(symbol "R_243k_0402_0_1"
				(rectangle
					(start 0.635 0.889)
					(end 4.445 -0.889)
					(stroke
						(width 0.254)
						(type default)
					)
					(fill
						(type none)
					)
				)
			)
			(symbol "R_243k_0402_1_1"
				(pin passive line
					(at 0 0 0)
					(length 0.635)
					(name "~"
						(effects
							(font
								(size 1.27 1.27)
							)
						)
					)
					(number "1"
						(effects
							(font
								(size 1.27 1.27)
							)
						)
					)
				)
				(pin passive line
					(at 5.08 0 180)
					(length 0.635)
					(name "~"
						(effects
							(font
								(size 1.27 1.27)
							)
						)
					)
					(number "2"
						(effects
							(font
								(size 1.27 1.27)
							)
						)
					)
				)
			)
		)
	(symbol "antmicroResistors0402:R_2k2_0402"
			(pin_numbers
				(hide yes)
			)
			(pin_names
				(hide yes)
			)
			(exclude_from_sim no)
			(in_bom yes)
			(on_board yes)
			(property "Reference" "R"
				(at 20.32 -5.08 0)
				(effects
					(font
						(size 1.27 1.27)
						(thickness 0.15)
					)
					(justify left bottom)
				)
			)
			(property "Value" "R_2k2_0402"
				(at 20.32 -12.7 0)
				(effects
					(font
						(size 1.27 1.27)
						(thickness 0.15)
					)
					(justify left bottom)
					(hide yes)
				)
			)
			(property "Footprint" "antmicro-footprints:R_0402_1005Metric"
				(at 20.32 -15.24 0)
				(effects
					(font
						(size 1.27 1.27)
						(thickness 0.15)
					)
					(justify left bottom)
					(hide yes)
				)
			)
			(property "Datasheet" "https://www.bourns.com/docs/product-datasheets/cr.pdf"
				(at 20.32 -17.78 0)
				(effects
					(font
						(size 1.27 1.27)
						(thickness 0.15)
					)
					(justify left bottom)
					(hide yes)
				)
			)
			(property "Description" "2k2 resistor in 0402 package with 1% tolerance"
				(at 0 0 0)
				(effects
					(font
						(size 1.27 1.27)
					)
					(hide yes)
				)
			)
			(property "MPN" "CR0402-FX-2201GLF"
				(at 20.32 -20.32 0)
				(effects
					(font
						(size 1.27 1.27)
						(thickness 0.15)
					)
					(justify left bottom)
					(hide yes)
				)
			)
			(property "Manufacturer" "Bourns"
				(at 20.32 -22.86 0)
				(effects
					(font
						(size 1.27 1.27)
						(thickness 0.15)
					)
					(justify left bottom)
					(hide yes)
				)
			)
			(property "License" "Apache-2.0"
				(at 20.32 -25.4 0)
				(effects
					(font
						(size 1.27 1.27)
						(thickness 0.15)
					)
					(justify left bottom)
					(hide yes)
				)
			)
			(property "Author" "Antmicro"
				(at 20.32 -27.94 0)
				(effects
					(font
						(size 1.27 1.27)
						(thickness 0.15)
					)
					(justify left bottom)
					(hide yes)
				)
			)
			(property "Val" "2k2"
				(at 20.32 -7.62 0)
				(effects
					(font
						(size 1.27 1.27)
						(thickness 0.15)
					)
					(justify left bottom)
				)
			)
			(property "Tolerance" "1%"
				(at 20.32 -10.16 0)
				(effects
					(font
						(size 1.27 1.27)
					)
					(justify left bottom)
					(hide yes)
				)
			)
			(symbol "R_2k2_0402_0_1"
				(rectangle
					(start 0.635 0.889)
					(end 4.445 -0.889)
					(stroke
						(width 0.254)
						(type default)
					)
					(fill
						(type none)
					)
				)
			)
			(symbol "R_2k2_0402_1_1"
				(pin passive line
					(at 0 0 0)
					(length 0.635)
					(name "~"
						(effects
							(font
								(size 1.27 1.27)
							)
						)
					)
					(number "1"
						(effects
							(font
								(size 1.27 1.27)
							)
						)
					)
				)
				(pin passive line
					(at 5.08 0 180)
					(length 0.635)
					(name "~"
						(effects
							(font
								(size 1.27 1.27)
							)
						)
					)
					(number "2"
						(effects
							(font
								(size 1.27 1.27)
							)
						)
					)
				)
			)
		)
	(symbol "antmicroResistors0402:R_31k6_0402"
			(pin_numbers
				(hide yes)
			)
			(pin_names
				(hide yes)
			)
			(exclude_from_sim no)
			(in_bom yes)
			(on_board yes)
			(property "Reference" "R"
				(at 20.32 -5.08 0)
				(effects
					(font
						(size 1.27 1.27)
						(thickness 0.15)
					)
					(justify left bottom)
				)
			)
			(property "Value" "R_31k6_0402"
				(at 20.32 -12.7 0)
				(effects
					(font
						(size 1.27 1.27)
						(thickness 0.15)
					)
					(justify left bottom)
					(hide yes)
				)
			)
			(property "Footprint" "antmicro-footprints:R_0402_1005Metric"
				(at 20.32 -15.24 0)
				(effects
					(font
						(size 1.27 1.27)
						(thickness 0.15)
					)
					(justify left bottom)
					(hide yes)
				)
			)
			(property "Datasheet" "https://www.bourns.com/docs/product-datasheets/cr.pdf"
				(at 20.32 -17.78 0)
				(effects
					(font
						(size 1.27 1.27)
						(thickness 0.15)
					)
					(justify left bottom)
					(hide yes)
				)
			)
			(property "Description" "31k6 resistor in 0402 package with 1% tolerance"
				(at 0 0 0)
				(effects
					(font
						(size 1.27 1.27)
					)
					(hide yes)
				)
			)
			(property "MPN" "CR0402-FX-3162GLF"
				(at 20.32 -20.32 0)
				(effects
					(font
						(size 1.27 1.27)
						(thickness 0.15)
					)
					(justify left bottom)
					(hide yes)
				)
			)
			(property "Manufacturer" "Bourns"
				(at 20.32 -22.86 0)
				(effects
					(font
						(size 1.27 1.27)
						(thickness 0.15)
					)
					(justify left bottom)
					(hide yes)
				)
			)
			(property "License" "Apache-2.0"
				(at 20.32 -25.4 0)
				(effects
					(font
						(size 1.27 1.27)
						(thickness 0.15)
					)
					(justify left bottom)
					(hide yes)
				)
			)
			(property "Author" "Antmicro"
				(at 20.32 -27.94 0)
				(effects
					(font
						(size 1.27 1.27)
						(thickness 0.15)
					)
					(justify left bottom)
					(hide yes)
				)
			)
			(property "Val" "31k6"
				(at 20.32 -7.62 0)
				(effects
					(font
						(size 1.27 1.27)
						(thickness 0.15)
					)
					(justify left bottom)
				)
			)
			(property "Tolerance" "1%"
				(at 20.32 -10.16 0)
				(effects
					(font
						(size 1.27 1.27)
					)
					(justify left bottom)
					(hide yes)
				)
			)
			(symbol "R_31k6_0402_0_1"
				(rectangle
					(start 0.635 0.889)
					(end 4.445 -0.889)
					(stroke
						(width 0.254)
						(type default)
					)
					(fill
						(type none)
					)
				)
			)
			(symbol "R_31k6_0402_1_1"
				(pin passive line
					(at 0 0 0)
					(length 0.635)
					(name "~"
						(effects
							(font
								(size 1.27 1.27)
							)
						)
					)
					(number "1"
						(effects
							(font
								(size 1.27 1.27)
							)
						)
					)
				)
				(pin passive line
					(at 5.08 0 180)
					(length 0.635)
					(name "~"
						(effects
							(font
								(size 1.27 1.27)
							)
						)
					)
					(number "2"
						(effects
							(font
								(size 1.27 1.27)
							)
						)
					)
				)
			)
		)
	(symbol "antmicroResistors0402:R_330R_0402"
			(pin_numbers
				(hide yes)
			)
			(pin_names
				(hide yes)
			)
			(exclude_from_sim no)
			(in_bom yes)
			(on_board yes)
			(property "Reference" "R"
				(at 20.32 -5.08 0)
				(effects
					(font
						(size 1.27 1.27)
						(thickness 0.15)
					)
					(justify left bottom)
				)
			)
			(property "Value" "R_330R_0402"
				(at 20.32 -12.7 0)
				(effects
					(font
						(size 1.27 1.27)
						(thickness 0.15)
					)
					(justify left bottom)
					(hide yes)
				)
			)
			(property "Footprint" "antmicro-footprints:R_0402_1005Metric"
				(at 20.32 -15.24 0)
				(effects
					(font
						(size 1.27 1.27)
						(thickness 0.15)
					)
					(justify left bottom)
					(hide yes)
				)
			)
			(property "Datasheet" "https://www.bourns.com/docs/product-datasheets/cr.pdf"
				(at 20.32 -17.78 0)
				(effects
					(font
						(size 1.27 1.27)
						(thickness 0.15)
					)
					(justify left bottom)
					(hide yes)
				)
			)
			(property "Description" "330R resistor in 0402 package with 1% tolerance"
				(at 0 0 0)
				(effects
					(font
						(size 1.27 1.27)
					)
					(hide yes)
				)
			)
			(property "MPN" "CR0402-FX-3300GLF"
				(at 20.32 -20.32 0)
				(effects
					(font
						(size 1.27 1.27)
						(thickness 0.15)
					)
					(justify left bottom)
					(hide yes)
				)
			)
			(property "Manufacturer" "Bourns"
				(at 20.32 -22.86 0)
				(effects
					(font
						(size 1.27 1.27)
						(thickness 0.15)
					)
					(justify left bottom)
					(hide yes)
				)
			)
			(property "License" "Apache-2.0"
				(at 20.32 -25.4 0)
				(effects
					(font
						(size 1.27 1.27)
						(thickness 0.15)
					)
					(justify left bottom)
					(hide yes)
				)
			)
			(property "Author" "Antmicro"
				(at 20.32 -27.94 0)
				(effects
					(font
						(size 1.27 1.27)
						(thickness 0.15)
					)
					(justify left bottom)
					(hide yes)
				)
			)
			(property "Val" "330R"
				(at 20.32 -7.62 0)
				(effects
					(font
						(size 1.27 1.27)
						(thickness 0.15)
					)
					(justify left bottom)
				)
			)
			(property "Tolerance" "1%"
				(at 20.32 -10.16 0)
				(effects
					(font
						(size 1.27 1.27)
					)
					(justify left bottom)
					(hide yes)
				)
			)
			(symbol "R_330R_0402_0_1"
				(rectangle
					(start 0.635 0.889)
					(end 4.445 -0.889)
					(stroke
						(width 0.254)
						(type default)
					)
					(fill
						(type none)
					)
				)
			)
			(symbol "R_330R_0402_1_1"
				(pin passive line
					(at 0 0 0)
					(length 0.635)
					(name "~"
						(effects
							(font
								(size 1.27 1.27)
							)
						)
					)
					(number "1"
						(effects
							(font
								(size 1.27 1.27)
							)
						)
					)
				)
				(pin passive line
					(at 5.08 0 180)
					(length 0.635)
					(name "~"
						(effects
							(font
								(size 1.27 1.27)
							)
						)
					)
					(number "2"
						(effects
							(font
								(size 1.27 1.27)
							)
						)
					)
				)
			)
		)
	(symbol "antmicroResistors0402:R_49R9_0402"
			(pin_numbers
				(hide yes)
			)
			(pin_names
				(hide yes)
			)
			(exclude_from_sim no)
			(in_bom yes)
			(on_board yes)
			(property "Reference" "R"
				(at 20.32 -5.08 0)
				(effects
					(font
						(size 1.27 1.27)
						(thickness 0.15)
					)
					(justify left bottom)
				)
			)
			(property "Value" "R_49R9_0402"
				(at 20.32 -12.7 0)
				(effects
					(font
						(size 1.27 1.27)
						(thickness 0.15)
					)
					(justify left bottom)
					(hide yes)
				)
			)
			(property "Footprint" "antmicro-footprints:R_0402_1005Metric"
				(at 20.32 -15.24 0)
				(effects
					(font
						(size 1.27 1.27)
						(thickness 0.15)
					)
					(justify left bottom)
					(hide yes)
				)
			)
			(property "Datasheet" "https://www.bourns.com/docs/product-datasheets/cr.pdf"
				(at 20.32 -17.78 0)
				(effects
					(font
						(size 1.27 1.27)
						(thickness 0.15)
					)
					(justify left bottom)
					(hide yes)
				)
			)
			(property "Description" "49R9 resistor in 0402 package with 1% tolerance"
				(at 0 0 0)
				(effects
					(font
						(size 1.27 1.27)
					)
					(hide yes)
				)
			)
			(property "MPN" "CR0402-FX-49R9GLF"
				(at 20.32 -20.32 0)
				(effects
					(font
						(size 1.27 1.27)
						(thickness 0.15)
					)
					(justify left bottom)
					(hide yes)
				)
			)
			(property "Manufacturer" "Bourns"
				(at 20.32 -22.86 0)
				(effects
					(font
						(size 1.27 1.27)
						(thickness 0.15)
					)
					(justify left bottom)
					(hide yes)
				)
			)
			(property "License" "Apache-2.0"
				(at 20.32 -25.4 0)
				(effects
					(font
						(size 1.27 1.27)
						(thickness 0.15)
					)
					(justify left bottom)
					(hide yes)
				)
			)
			(property "Author" "Antmicro"
				(at 20.32 -27.94 0)
				(effects
					(font
						(size 1.27 1.27)
						(thickness 0.15)
					)
					(justify left bottom)
					(hide yes)
				)
			)
			(property "Val" "49R9"
				(at 20.32 -7.62 0)
				(effects
					(font
						(size 1.27 1.27)
						(thickness 0.15)
					)
					(justify left bottom)
				)
			)
			(property "Tolerance" "1%"
				(at 20.32 -10.16 0)
				(effects
					(font
						(size 1.27 1.27)
					)
					(justify left bottom)
					(hide yes)
				)
			)
			(symbol "R_49R9_0402_0_1"
				(rectangle
					(start 0.635 0.889)
					(end 4.445 -0.889)
					(stroke
						(width 0.254)
						(type default)
					)
					(fill
						(type none)
					)
				)
			)
			(symbol "R_49R9_0402_1_1"
				(pin passive line
					(at 0 0 0)
					(length 0.635)
					(name "~"
						(effects
							(font
								(size 1.27 1.27)
							)
						)
					)
					(number "1"
						(effects
							(font
								(size 1.27 1.27)
							)
						)
					)
				)
				(pin passive line
					(at 5.08 0 180)
					(length 0.635)
					(name "~"
						(effects
							(font
								(size 1.27 1.27)
							)
						)
					)
					(number "2"
						(effects
							(font
								(size 1.27 1.27)
							)
						)
					)
				)
			)
		)
	(symbol "antmicroResistors0402:R_4k7_0402"
			(pin_numbers
				(hide yes)
			)
			(pin_names
				(hide yes)
			)
			(exclude_from_sim no)
			(in_bom yes)
			(on_board yes)
			(property "Reference" "R"
				(at 20.32 -5.08 0)
				(effects
					(font
						(size 1.27 1.27)
						(thickness 0.15)
					)
					(justify left bottom)
				)
			)
			(property "Value" "R_4k7_0402"
				(at 20.32 -12.7 0)
				(effects
					(font
						(size 1.27 1.27)
						(thickness 0.15)
					)
					(justify left bottom)
					(hide yes)
				)
			)
			(property "Footprint" "antmicro-footprints:R_0402_1005Metric"
				(at 20.32 -15.24 0)
				(effects
					(font
						(size 1.27 1.27)
						(thickness 0.15)
					)
					(justify left bottom)
					(hide yes)
				)
			)
			(property "Datasheet" "https://www.bourns.com/docs/product-datasheets/cr.pdf"
				(at 20.32 -17.78 0)
				(effects
					(font
						(size 1.27 1.27)
						(thickness 0.15)
					)
					(justify left bottom)
					(hide yes)
				)
			)
			(property "Description" "4k7 resistor in 0402 package with 1% tolerance"
				(at 0 0 0)
				(effects
					(font
						(size 1.27 1.27)
					)
					(hide yes)
				)
			)
			(property "MPN" "CR0402-FX-4701GLF"
				(at 20.32 -20.32 0)
				(effects
					(font
						(size 1.27 1.27)
						(thickness 0.15)
					)
					(justify left bottom)
					(hide yes)
				)
			)
			(property "Manufacturer" "Bourns"
				(at 20.32 -22.86 0)
				(effects
					(font
						(size 1.27 1.27)
						(thickness 0.15)
					)
					(justify left bottom)
					(hide yes)
				)
			)
			(property "License" "Apache-2.0"
				(at 20.32 -25.4 0)
				(effects
					(font
						(size 1.27 1.27)
						(thickness 0.15)
					)
					(justify left bottom)
					(hide yes)
				)
			)
			(property "Author" "Antmicro"
				(at 20.32 -27.94 0)
				(effects
					(font
						(size 1.27 1.27)
						(thickness 0.15)
					)
					(justify left bottom)
					(hide yes)
				)
			)
			(property "Val" "4k7"
				(at 20.32 -7.62 0)
				(effects
					(font
						(size 1.27 1.27)
						(thickness 0.15)
					)
					(justify left bottom)
				)
			)
			(property "Tolerance" "1%"
				(at 20.32 -10.16 0)
				(effects
					(font
						(size 1.27 1.27)
					)
					(justify left bottom)
					(hide yes)
				)
			)
			(symbol "R_4k7_0402_0_1"
				(rectangle
					(start 0.635 0.889)
					(end 4.445 -0.889)
					(stroke
						(width 0.254)
						(type default)
					)
					(fill
						(type none)
					)
				)
			)
			(symbol "R_4k7_0402_1_1"
				(pin passive line
					(at 0 0 0)
					(length 0.635)
					(name "~"
						(effects
							(font
								(size 1.27 1.27)
							)
						)
					)
					(number "1"
						(effects
							(font
								(size 1.27 1.27)
							)
						)
					)
				)
				(pin passive line
					(at 5.08 0 180)
					(length 0.635)
					(name "~"
						(effects
							(font
								(size 1.27 1.27)
							)
						)
					)
					(number "2"
						(effects
							(font
								(size 1.27 1.27)
							)
						)
					)
				)
			)
		)
	(symbol "antmicroResistors0402:R_53k6_0402"
			(pin_numbers
				(hide yes)
			)
			(pin_names
				(hide yes)
			)
			(exclude_from_sim no)
			(in_bom yes)
			(on_board yes)
			(property "Reference" "R"
				(at 20.32 -5.08 0)
				(effects
					(font
						(size 1.27 1.27)
						(thickness 0.15)
					)
					(justify left bottom)
				)
			)
			(property "Value" "R_53k6_0402"
				(at 20.32 -12.7 0)
				(effects
					(font
						(size 1.27 1.27)
						(thickness 0.15)
					)
					(justify left bottom)
					(hide yes)
				)
			)
			(property "Footprint" "antmicro-footprints:R_0402_1005Metric"
				(at 20.32 -15.24 0)
				(effects
					(font
						(size 1.27 1.27)
						(thickness 0.15)
					)
					(justify left bottom)
					(hide yes)
				)
			)
			(property "Datasheet" "https://www.bourns.com/docs/product-datasheets/cr.pdf"
				(at 20.32 -17.78 0)
				(effects
					(font
						(size 1.27 1.27)
						(thickness 0.15)
					)
					(justify left bottom)
					(hide yes)
				)
			)
			(property "Description" "53k6 resistor in 0402 package with 1% tolerance"
				(at 0 0 0)
				(effects
					(font
						(size 1.27 1.27)
					)
					(hide yes)
				)
			)
			(property "MPN" "CR0402-FX-5362GLF"
				(at 20.32 -20.32 0)
				(effects
					(font
						(size 1.27 1.27)
						(thickness 0.15)
					)
					(justify left bottom)
					(hide yes)
				)
			)
			(property "Manufacturer" "Bourns"
				(at 20.32 -22.86 0)
				(effects
					(font
						(size 1.27 1.27)
						(thickness 0.15)
					)
					(justify left bottom)
					(hide yes)
				)
			)
			(property "License" "Apache-2.0"
				(at 20.32 -25.4 0)
				(effects
					(font
						(size 1.27 1.27)
						(thickness 0.15)
					)
					(justify left bottom)
					(hide yes)
				)
			)
			(property "Author" "Antmicro"
				(at 20.32 -27.94 0)
				(effects
					(font
						(size 1.27 1.27)
						(thickness 0.15)
					)
					(justify left bottom)
					(hide yes)
				)
			)
			(property "Val" "53k6"
				(at 20.32 -7.62 0)
				(effects
					(font
						(size 1.27 1.27)
						(thickness 0.15)
					)
					(justify left bottom)
				)
			)
			(property "Tolerance" "1%"
				(at 20.32 -10.16 0)
				(effects
					(font
						(size 1.27 1.27)
					)
					(justify left bottom)
					(hide yes)
				)
			)
			(symbol "R_53k6_0402_0_1"
				(rectangle
					(start 0.635 0.889)
					(end 4.445 -0.889)
					(stroke
						(width 0.254)
						(type default)
					)
					(fill
						(type none)
					)
				)
			)
			(symbol "R_53k6_0402_1_1"
				(pin passive line
					(at 0 0 0)
					(length 0.635)
					(name "~"
						(effects
							(font
								(size 1.27 1.27)
							)
						)
					)
					(number "1"
						(effects
							(font
								(size 1.27 1.27)
							)
						)
					)
				)
				(pin passive line
					(at 5.08 0 180)
					(length 0.635)
					(name "~"
						(effects
							(font
								(size 1.27 1.27)
							)
						)
					)
					(number "2"
						(effects
							(font
								(size 1.27 1.27)
							)
						)
					)
				)
			)
		)
	(symbol "antmicroResistors0402:R_5R1_0402"
			(pin_numbers
				(hide yes)
			)
			(pin_names
				(hide yes)
			)
			(exclude_from_sim no)
			(in_bom yes)
			(on_board yes)
			(property "Reference" "R"
				(at 20.32 -5.08 0)
				(effects
					(font
						(size 1.27 1.27)
						(thickness 0.15)
					)
					(justify left bottom)
				)
			)
			(property "Value" "R_5R1_0402"
				(at 20.32 -12.7 0)
				(effects
					(font
						(size 1.27 1.27)
						(thickness 0.15)
					)
					(justify left bottom)
					(hide yes)
				)
			)
			(property "Footprint" "antmicro-footprints:R_0402_1005Metric"
				(at 20.32 -15.24 0)
				(effects
					(font
						(size 1.27 1.27)
						(thickness 0.15)
					)
					(justify left bottom)
					(hide yes)
				)
			)
			(property "Datasheet" "https://www.bourns.com/docs/product-datasheets/cr.pdf"
				(at 20.32 -17.78 0)
				(effects
					(font
						(size 1.27 1.27)
						(thickness 0.15)
					)
					(justify left bottom)
					(hide yes)
				)
			)
			(property "Description" "5R1 resistor in 0402 package with 1% tolerance"
				(at 0 0 0)
				(effects
					(font
						(size 1.27 1.27)
					)
					(hide yes)
				)
			)
			(property "MPN" "CR0402-FX-5R10GLF"
				(at 20.32 -20.32 0)
				(effects
					(font
						(size 1.27 1.27)
						(thickness 0.15)
					)
					(justify left bottom)
					(hide yes)
				)
			)
			(property "Manufacturer" "Bourns"
				(at 20.32 -22.86 0)
				(effects
					(font
						(size 1.27 1.27)
						(thickness 0.15)
					)
					(justify left bottom)
					(hide yes)
				)
			)
			(property "License" "Apache-2.0"
				(at 20.32 -25.4 0)
				(effects
					(font
						(size 1.27 1.27)
						(thickness 0.15)
					)
					(justify left bottom)
					(hide yes)
				)
			)
			(property "Author" "Antmicro"
				(at 20.32 -27.94 0)
				(effects
					(font
						(size 1.27 1.27)
						(thickness 0.15)
					)
					(justify left bottom)
					(hide yes)
				)
			)
			(property "Val" "5R1"
				(at 20.32 -7.62 0)
				(effects
					(font
						(size 1.27 1.27)
						(thickness 0.15)
					)
					(justify left bottom)
				)
			)
			(property "Tolerance" "1%"
				(at 20.32 -10.16 0)
				(effects
					(font
						(size 1.27 1.27)
					)
					(justify left bottom)
					(hide yes)
				)
			)
			(symbol "R_5R1_0402_0_1"
				(rectangle
					(start 0.635 0.889)
					(end 4.445 -0.889)
					(stroke
						(width 0.254)
						(type default)
					)
					(fill
						(type none)
					)
				)
			)
			(symbol "R_5R1_0402_1_1"
				(pin passive line
					(at 0 0 0)
					(length 0.635)
					(name "~"
						(effects
							(font
								(size 1.27 1.27)
							)
						)
					)
					(number "1"
						(effects
							(font
								(size 1.27 1.27)
							)
						)
					)
				)
				(pin passive line
					(at 5.08 0 180)
					(length 0.635)
					(name "~"
						(effects
							(font
								(size 1.27 1.27)
							)
						)
					)
					(number "2"
						(effects
							(font
								(size 1.27 1.27)
							)
						)
					)
				)
			)
		)
	(symbol "antmicroResistors0603:R_120R_0603"
			(pin_numbers
				(hide yes)
			)
			(pin_names
				(hide yes)
			)
			(exclude_from_sim no)
			(in_bom yes)
			(on_board yes)
			(property "Reference" "R"
				(at 20.32 -5.08 0)
				(effects
					(font
						(size 1.27 1.27)
						(thickness 0.15)
					)
					(justify left bottom)
				)
			)
			(property "Value" "R_120R_0603"
				(at 20.32 -12.7 0)
				(effects
					(font
						(size 1.27 1.27)
						(thickness 0.15)
					)
					(justify left bottom)
					(hide yes)
				)
			)
			(property "Footprint" "antmicro-footprints:R_0603_1608Metric"
				(at 20.32 -15.24 0)
				(effects
					(font
						(size 1.27 1.27)
						(thickness 0.15)
					)
					(justify left bottom)
					(hide yes)
				)
			)
			(property "Datasheet" "https://www.bourns.com/docs/product-datasheets/cr.pdf"
				(at 20.32 -17.78 0)
				(effects
					(font
						(size 1.27 1.27)
						(thickness 0.15)
					)
					(justify left bottom)
					(hide yes)
				)
			)
			(property "Description" "120R resistor in 0603 package with 1% tolerance"
				(at 0 0 0)
				(effects
					(font
						(size 1.27 1.27)
					)
					(hide yes)
				)
			)
			(property "MPN" "CR0603-FX-1200ELF"
				(at 20.32 -20.32 0)
				(effects
					(font
						(size 1.27 1.27)
						(thickness 0.15)
					)
					(justify left bottom)
					(hide yes)
				)
			)
			(property "Manufacturer" "Bourns"
				(at 20.32 -22.86 0)
				(effects
					(font
						(size 1.27 1.27)
						(thickness 0.15)
					)
					(justify left bottom)
					(hide yes)
				)
			)
			(property "License" "Apache-2.0"
				(at 20.32 -25.4 0)
				(effects
					(font
						(size 1.27 1.27)
						(thickness 0.15)
					)
					(justify left bottom)
					(hide yes)
				)
			)
			(property "Author" "Antmicro"
				(at 20.32 -27.94 0)
				(effects
					(font
						(size 1.27 1.27)
						(thickness 0.15)
					)
					(justify left bottom)
					(hide yes)
				)
			)
			(property "Val" "120R"
				(at 20.32 -7.62 0)
				(effects
					(font
						(size 1.27 1.27)
						(thickness 0.15)
					)
					(justify left bottom)
				)
			)
			(property "Tolerance" "1%"
				(at 20.32 -10.16 0)
				(effects
					(font
						(size 1.27 1.27)
					)
					(justify left bottom)
					(hide yes)
				)
			)
			(symbol "R_120R_0603_0_1"
				(rectangle
					(start 0.635 0.889)
					(end 4.445 -0.889)
					(stroke
						(width 0.254)
						(type default)
					)
					(fill
						(type none)
					)
				)
			)
			(symbol "R_120R_0603_1_1"
				(pin passive line
					(at 0 0 0)
					(length 0.635)
					(name "~"
						(effects
							(font
								(size 1.27 1.27)
							)
						)
					)
					(number "1"
						(effects
							(font
								(size 1.27 1.27)
							)
						)
					)
				)
				(pin passive line
					(at 5.08 0 180)
					(length 0.635)
					(name "~"
						(effects
							(font
								(size 1.27 1.27)
							)
						)
					)
					(number "2"
						(effects
							(font
								(size 1.27 1.27)
							)
						)
					)
				)
			)
		)
	(symbol "antmicroResistors0603:R_1k_0603"
			(pin_numbers
				(hide yes)
			)
			(pin_names
				(hide yes)
			)
			(exclude_from_sim no)
			(in_bom yes)
			(on_board yes)
			(property "Reference" "R"
				(at 20.32 -5.08 0)
				(effects
					(font
						(size 1.27 1.27)
						(thickness 0.15)
					)
					(justify left bottom)
				)
			)
			(property "Value" "R_1k_0603"
				(at 20.32 -12.7 0)
				(effects
					(font
						(size 1.27 1.27)
						(thickness 0.15)
					)
					(justify left bottom)
					(hide yes)
				)
			)
			(property "Footprint" "antmicro-footprints:R_0603_1608Metric"
				(at 20.32 -15.24 0)
				(effects
					(font
						(size 1.27 1.27)
						(thickness 0.15)
					)
					(justify left bottom)
					(hide yes)
				)
			)
			(property "Datasheet" "https://www.bourns.com/docs/product-datasheets/cr.pdf"
				(at 20.32 -17.78 0)
				(effects
					(font
						(size 1.27 1.27)
						(thickness 0.15)
					)
					(justify left bottom)
					(hide yes)
				)
			)
			(property "Description" "1k resistor in 0603 package with 1% tolerance"
				(at 0 0 0)
				(effects
					(font
						(size 1.27 1.27)
					)
					(hide yes)
				)
			)
			(property "MPN" "CR0603-FX-1001ELF"
				(at 20.32 -20.32 0)
				(effects
					(font
						(size 1.27 1.27)
						(thickness 0.15)
					)
					(justify left bottom)
					(hide yes)
				)
			)
			(property "Manufacturer" "Bourns"
				(at 20.32 -22.86 0)
				(effects
					(font
						(size 1.27 1.27)
						(thickness 0.15)
					)
					(justify left bottom)
					(hide yes)
				)
			)
			(property "License" "Apache-2.0"
				(at 20.32 -25.4 0)
				(effects
					(font
						(size 1.27 1.27)
						(thickness 0.15)
					)
					(justify left bottom)
					(hide yes)
				)
			)
			(property "Author" "Antmicro"
				(at 20.32 -27.94 0)
				(effects
					(font
						(size 1.27 1.27)
						(thickness 0.15)
					)
					(justify left bottom)
					(hide yes)
				)
			)
			(property "Val" "1k"
				(at 20.32 -7.62 0)
				(effects
					(font
						(size 1.27 1.27)
						(thickness 0.15)
					)
					(justify left bottom)
				)
			)
			(property "Tolerance" "1%"
				(at 20.32 -10.16 0)
				(effects
					(font
						(size 1.27 1.27)
					)
					(justify left bottom)
					(hide yes)
				)
			)
			(symbol "R_1k_0603_0_1"
				(rectangle
					(start 0.635 0.889)
					(end 4.445 -0.889)
					(stroke
						(width 0.254)
						(type default)
					)
					(fill
						(type none)
					)
				)
			)
			(symbol "R_1k_0603_1_1"
				(pin passive line
					(at 0 0 0)
					(length 0.635)
					(name "~"
						(effects
							(font
								(size 1.27 1.27)
							)
						)
					)
					(number "1"
						(effects
							(font
								(size 1.27 1.27)
							)
						)
					)
				)
				(pin passive line
					(at 5.08 0 180)
					(length 0.635)
					(name "~"
						(effects
							(font
								(size 1.27 1.27)
							)
						)
					)
					(number "2"
						(effects
							(font
								(size 1.27 1.27)
							)
						)
					)
				)
			)
		)
	(symbol "antmicroResistorsmisc:R_0R_0805"
			(pin_numbers
				(hide yes)
			)
			(pin_names
				(hide yes)
			)
			(exclude_from_sim no)
			(in_bom yes)
			(on_board yes)
			(property "Reference" "R"
				(at 20.32 -5.08 0)
				(effects
					(font
						(size 1.27 1.27)
						(thickness 0.15)
					)
					(justify left bottom)
				)
			)
			(property "Value" "R_0R_0805"
				(at 20.32 -12.7 0)
				(effects
					(font
						(size 1.27 1.27)
						(thickness 0.15)
					)
					(justify left bottom)
					(hide yes)
				)
			)
			(property "Footprint" "antmicro-footprints:R_0805_2012Metric"
				(at 20.32 -15.24 0)
				(effects
					(font
						(size 1.27 1.27)
						(thickness 0.15)
					)
					(justify left bottom)
					(hide yes)
				)
			)
			(property "Datasheet" "https://www.vishay.com/docs/20035/dcrcwe3.pdf"
				(at 20.32 -17.78 0)
				(effects
					(font
						(size 1.27 1.27)
						(thickness 0.15)
					)
					(justify left bottom)
					(hide yes)
				)
			)
			(property "Description" "0R resistor in 0805 package with unspecified tolerance"
				(at 0 0 0)
				(effects
					(font
						(size 1.27 1.27)
					)
					(hide yes)
				)
			)
			(property "MPN" "CRCW08050000Z0EA"
				(at 20.32 -20.32 0)
				(effects
					(font
						(size 1.27 1.27)
						(thickness 0.15)
					)
					(justify left bottom)
					(hide yes)
				)
			)
			(property "Manufacturer" "Vishay"
				(at 20.32 -22.86 0)
				(effects
					(font
						(size 1.27 1.27)
						(thickness 0.15)
					)
					(justify left bottom)
					(hide yes)
				)
			)
			(property "License" "Apache-2.0"
				(at 20.32 -25.4 0)
				(effects
					(font
						(size 1.27 1.27)
						(thickness 0.15)
					)
					(justify left bottom)
					(hide yes)
				)
			)
			(property "Author" "Antmicro"
				(at 20.32 -27.94 0)
				(effects
					(font
						(size 1.27 1.27)
						(thickness 0.15)
					)
					(justify left bottom)
					(hide yes)
				)
			)
			(property "Val" "0R"
				(at 20.32 -7.62 0)
				(effects
					(font
						(size 1.27 1.27)
						(thickness 0.15)
					)
					(justify left bottom)
				)
			)
			(property "Tolerance" "~"
				(at 20.32 -10.16 0)
				(effects
					(font
						(size 1.27 1.27)
					)
					(justify left bottom)
					(hide yes)
				)
			)
			(property "Current" "2.5A"
				(at 20.32 -30.48 0)
				(effects
					(font
						(size 1.27 1.27)
						(thickness 0.15)
					)
					(justify left bottom)
					(hide yes)
				)
			)
			(symbol "R_0R_0805_0_1"
				(rectangle
					(start 0.635 0.889)
					(end 4.445 -0.889)
					(stroke
						(width 0.254)
						(type default)
					)
					(fill
						(type none)
					)
				)
			)
			(symbol "R_0R_0805_1_1"
				(pin passive line
					(at 0 0 0)
					(length 0.635)
					(name "~"
						(effects
							(font
								(size 1.27 1.27)
							)
						)
					)
					(number "1"
						(effects
							(font
								(size 1.27 1.27)
							)
						)
					)
				)
				(pin passive line
					(at 5.08 0 180)
					(length 0.635)
					(name "~"
						(effects
							(font
								(size 1.27 1.27)
							)
						)
					)
					(number "2"
						(effects
							(font
								(size 1.27 1.27)
							)
						)
					)
				)
			)
		)
	(symbol "antmicroResonators:Resonator_12MHz_ABM8G"
			(pin_names
				(hide yes)
			)
			(exclude_from_sim no)
			(in_bom yes)
			(on_board yes)
			(property "Reference" "Y"
				(at 15.24 -5.08 0)
				(effects
					(font
						(size 1.27 1.27)
						(thickness 0.15)
					)
					(justify left bottom)
				)
			)
			(property "Value" "Resonator_12MHz_ABM8G"
				(at 15.24 -12.7 0)
				(effects
					(font
						(size 1.27 1.27)
						(thickness 0.15)
					)
					(justify left bottom)
					(hide yes)
				)
			)
			(property "Footprint" "antmicro-footprints:Resonator_SMD_Abracon_ABM8G_3.2x2.5mm"
				(at 15.24 -15.24 0)
				(effects
					(font
						(size 1.27 1.27)
						(thickness 0.15)
					)
					(justify left bottom)
					(hide yes)
				)
			)
			(property "Datasheet" "https://abracon.com/Resonators/ABM8G.pdf"
				(at 15.24 -17.78 0)
				(effects
					(font
						(size 1.27 1.27)
						(thickness 0.15)
					)
					(justify left bottom)
					(hide yes)
				)
			)
			(property "Description" "Crystal, 12 MHz, SMT, 3.2mm x 2.5mm, 30 ppm, 18 pF, 20 ppm, ABM8G"
				(at 0 0 0)
				(effects
					(font
						(size 1.27 1.27)
					)
					(hide yes)
				)
			)
			(property "MPN" "ABM8G-12.000MHZ-18-D2Y-T"
				(at 15.24 -7.62 0)
				(effects
					(font
						(size 1.27 1.27)
						(thickness 0.15)
					)
					(justify left bottom)
					(hide yes)
				)
			)
			(property "Manufacturer" "Abracon"
				(at 15.24 -20.32 0)
				(effects
					(font
						(size 1.27 1.27)
						(thickness 0.15)
					)
					(justify left bottom)
					(hide yes)
				)
			)
			(property "Author" "Antmicro"
				(at 15.24 -22.86 0)
				(effects
					(font
						(size 1.27 1.27)
						(thickness 0.15)
					)
					(justify left bottom)
					(hide yes)
				)
			)
			(property "License" "Apache-2.0"
				(at 15.24 -25.4 0)
				(effects
					(font
						(size 1.27 1.27)
						(thickness 0.15)
					)
					(justify left bottom)
					(hide yes)
				)
			)
			(property "Val" "12 MHz"
				(at 15.24 -10.16 0)
				(effects
					(font
						(size 1.27 1.27)
						(thickness 0.15)
					)
					(justify left bottom)
				)
			)
			(property "ki_keywords" "SMT, CERAMIC, OSCILLATOR"
				(at 0 0 0)
				(effects
					(font
						(size 1.27 1.27)
					)
					(hide yes)
				)
			)
			(symbol "Resonator_12MHz_ABM8G_1_1"
				(polyline
					(pts
						(xy 1.905 1.905) (xy 1.905 2.54) (xy 5.715 2.54) (xy 5.715 1.905)
					)
					(stroke
						(width 0.254)
						(type default)
					)
					(fill
						(type none)
					)
				)
				(polyline
					(pts
						(xy 1.905 -1.905) (xy 1.905 -2.54) (xy 5.715 -2.54) (xy 5.715 -1.905)
					)
					(stroke
						(width 0.254)
						(type default)
					)
					(fill
						(type none)
					)
				)
				(polyline
					(pts
						(xy 2.54 1.27) (xy 2.54 -1.27)
					)
					(stroke
						(width 0.254)
						(type default)
					)
					(fill
						(type background)
					)
				)
				(rectangle
					(start 3.175 1.905)
					(end 4.445 -1.905)
					(stroke
						(width 0.254)
						(type default)
					)
					(fill
						(type background)
					)
				)
				(polyline
					(pts
						(xy 5.08 1.27) (xy 5.08 -1.27)
					)
					(stroke
						(width 0.254)
						(type default)
					)
					(fill
						(type background)
					)
				)
				(pin passive line
					(at 0 0 0)
					(length 2.54)
					(name "~"
						(effects
							(font
								(size 1.27 1.27)
							)
						)
					)
					(number "1"
						(effects
							(font
								(size 1.27 1.27)
							)
						)
					)
				)
				(pin passive line
					(at 3.81 -5.08 90)
					(length 2.54)
					(name "SH"
						(effects
							(font
								(size 1.27 1.27)
							)
						)
					)
					(number "2"
						(effects
							(font
								(size 1.27 1.27)
							)
						)
					)
				)
				(pin passive line
					(at 3.81 -5.08 90)
					(length 2.54)
					(hide yes)
					(name "SH"
						(effects
							(font
								(size 1.27 1.27)
							)
						)
					)
					(number "4"
						(effects
							(font
								(size 1.27 1.27)
							)
						)
					)
				)
				(pin passive line
					(at 7.62 0 180)
					(length 2.54)
					(name "~"
						(effects
							(font
								(size 1.27 1.27)
							)
						)
					)
					(number "3"
						(effects
							(font
								(size 1.27 1.27)
							)
						)
					)
				)
			)
		)
	(symbol "antmicroResonators:Resonator_25MHz_ABM8G"
			(pin_names
				(hide yes)
			)
			(exclude_from_sim no)
			(in_bom yes)
			(on_board yes)
			(property "Reference" "Y"
				(at 15.24 -5.08 0)
				(effects
					(font
						(size 1.27 1.27)
						(thickness 0.15)
					)
					(justify left bottom)
				)
			)
			(property "Value" "Resonator_25MHz_ABM8G"
				(at 15.24 -12.7 0)
				(effects
					(font
						(size 1.27 1.27)
						(thickness 0.15)
					)
					(justify left bottom)
					(hide yes)
				)
			)
			(property "Footprint" "antmicro-footprints:Resonator_SMD_Abracon_ABM8G_3.2x2.5mm"
				(at 15.24 -15.24 0)
				(effects
					(font
						(size 1.27 1.27)
						(thickness 0.15)
					)
					(justify left bottom)
					(hide yes)
				)
			)
			(property "Datasheet" "https://abracon.com/Resonators/ABM8G.pdf"
				(at 15.24 -17.78 0)
				(effects
					(font
						(size 1.27 1.27)
						(thickness 0.15)
					)
					(justify left bottom)
					(hide yes)
				)
			)
			(property "Description" "Crystal, 25 MHz, SMD, 3.2mm x 2.5mm, 30 ppm, 18 pF, 20 ppm, ABM8G"
				(at 0 0 0)
				(effects
					(font
						(size 1.27 1.27)
					)
					(hide yes)
				)
			)
			(property "MPN" "ABM8G-25.000MHZ-18-D2Y-T3"
				(at 15.24 -7.62 0)
				(effects
					(font
						(size 1.27 1.27)
						(thickness 0.15)
					)
					(justify left bottom)
					(hide yes)
				)
			)
			(property "Manufacturer" "Abracon"
				(at 15.24 -20.32 0)
				(effects
					(font
						(size 1.27 1.27)
						(thickness 0.15)
					)
					(justify left bottom)
					(hide yes)
				)
			)
			(property "Author" "Antmicro"
				(at 15.24 -22.86 0)
				(effects
					(font
						(size 1.27 1.27)
						(thickness 0.15)
					)
					(justify left bottom)
					(hide yes)
				)
			)
			(property "License" "Apache-2.0"
				(at 15.24 -25.4 0)
				(effects
					(font
						(size 1.27 1.27)
						(thickness 0.15)
					)
					(justify left bottom)
					(hide yes)
				)
			)
			(property "Val" "25 MHz"
				(at 15.24 -10.16 0)
				(effects
					(font
						(size 1.27 1.27)
						(thickness 0.15)
					)
					(justify left bottom)
				)
			)
			(property "ki_keywords" "SMT, CERAMIC, OSCILLATOR"
				(at 0 0 0)
				(effects
					(font
						(size 1.27 1.27)
					)
					(hide yes)
				)
			)
			(symbol "Resonator_25MHz_ABM8G_1_1"
				(polyline
					(pts
						(xy 1.905 1.905) (xy 1.905 2.54) (xy 5.715 2.54) (xy 5.715 1.905)
					)
					(stroke
						(width 0.254)
						(type default)
					)
					(fill
						(type none)
					)
				)
				(polyline
					(pts
						(xy 1.905 -1.905) (xy 1.905 -2.54) (xy 5.715 -2.54) (xy 5.715 -1.905)
					)
					(stroke
						(width 0.254)
						(type default)
					)
					(fill
						(type none)
					)
				)
				(polyline
					(pts
						(xy 2.54 1.27) (xy 2.54 -1.27)
					)
					(stroke
						(width 0.254)
						(type default)
					)
					(fill
						(type background)
					)
				)
				(rectangle
					(start 3.175 1.905)
					(end 4.445 -1.905)
					(stroke
						(width 0.254)
						(type default)
					)
					(fill
						(type background)
					)
				)
				(polyline
					(pts
						(xy 5.08 1.27) (xy 5.08 -1.27)
					)
					(stroke
						(width 0.254)
						(type default)
					)
					(fill
						(type background)
					)
				)
				(pin passive line
					(at 0 0 0)
					(length 2.54)
					(name "~"
						(effects
							(font
								(size 1.27 1.27)
							)
						)
					)
					(number "1"
						(effects
							(font
								(size 1.27 1.27)
							)
						)
					)
				)
				(pin passive line
					(at 3.81 -5.08 90)
					(length 2.54)
					(name "SH"
						(effects
							(font
								(size 1.27 1.27)
							)
						)
					)
					(number "2"
						(effects
							(font
								(size 1.27 1.27)
							)
						)
					)
				)
				(pin passive line
					(at 3.81 -5.08 90)
					(length 2.54)
					(hide yes)
					(name "SH"
						(effects
							(font
								(size 1.27 1.27)
							)
						)
					)
					(number "4"
						(effects
							(font
								(size 1.27 1.27)
							)
						)
					)
				)
				(pin passive line
					(at 7.62 0 180)
					(length 2.54)
					(name "~"
						(effects
							(font
								(size 1.27 1.27)
							)
						)
					)
					(number "3"
						(effects
							(font
								(size 1.27 1.27)
							)
						)
					)
				)
			)
		)
	(symbol "antmicroSlideSwitches:SW_EG1218"
			(exclude_from_sim no)
			(in_bom yes)
			(on_board yes)
			(property "Reference" "SW"
				(at 25.4 -5.08 0)
				(effects
					(font
						(size 1.27 1.27)
						(thickness 0.15)
					)
					(justify left bottom)
				)
			)
			(property "Value" "SW_EG1218"
				(at 25.4 -7.62 0)
				(effects
					(font
						(size 1.27 1.27)
						(thickness 0.15)
					)
					(justify left bottom)
				)
			)
			(property "Footprint" "antmicro-footprints:SW_Slide_E-Switch_EG1218"
				(at 25.4 -10.16 0)
				(effects
					(font
						(size 1.27 1.27)
						(thickness 0.15)
					)
					(justify left bottom)
					(hide yes)
				)
			)
			(property "Datasheet" "https://www.tme.eu/Document/1d2d6ae5aacf9145a66729085fd4c381/P040040.pdf"
				(at 25.4 -12.7 0)
				(effects
					(font
						(size 1.27 1.27)
						(thickness 0.15)
					)
					(justify left bottom)
					(hide yes)
				)
			)
			(property "Description" "E-Switch Slide Switches PC MNT 3 PIN SLIDE"
				(at 0 0 0)
				(effects
					(font
						(size 1.27 1.27)
					)
					(hide yes)
				)
			)
			(property "MPN" "EG1218"
				(at 25.4 -15.24 0)
				(effects
					(font
						(size 1.27 1.27)
						(thickness 0.15)
					)
					(justify left bottom)
					(hide yes)
				)
			)
			(property "Manufacturer" "E-Switch"
				(at 25.4 -17.78 0)
				(effects
					(font
						(size 1.27 1.27)
						(thickness 0.15)
					)
					(justify left bottom)
					(hide yes)
				)
			)
			(property "Author" "Antmicro"
				(at 25.4 -20.32 0)
				(effects
					(font
						(size 1.27 1.27)
						(thickness 0.15)
					)
					(justify left bottom)
					(hide yes)
				)
			)
			(property "License" "Apache-2.0"
				(at 25.4 -22.86 0)
				(effects
					(font
						(size 1.27 1.27)
						(thickness 0.15)
					)
					(justify left bottom)
					(hide yes)
				)
			)
			(property "ki_keywords" "E-Switch Slide Switches PC MNT 3 PIN SLIDE"
				(at 0 0 0)
				(effects
					(font
						(size 1.27 1.27)
					)
					(hide yes)
				)
			)
			(symbol "SW_EG1218_1_1"
				(rectangle
					(start 2.54 3.81)
					(end 10.16 -3.81)
					(stroke
						(width 0)
						(type default)
					)
					(fill
						(type background)
					)
				)
				(polyline
					(pts
						(xy 3.81 0) (xy 2.54 0)
					)
					(stroke
						(width 0.254)
						(type default)
					)
					(fill
						(type none)
					)
				)
				(circle
					(center 4.064 0)
					(radius 0.3556)
					(stroke
						(width 0.254)
						(type default)
					)
					(fill
						(type outline)
					)
				)
				(polyline
					(pts
						(xy 4.318 0) (xy 9.398 2.286)
					)
					(stroke
						(width 0.254)
						(type default)
					)
					(fill
						(type background)
					)
				)
				(circle
					(center 8.636 -2.54)
					(radius 0.3556)
					(stroke
						(width 0.254)
						(type default)
					)
					(fill
						(type outline)
					)
				)
				(circle
					(center 8.89 2.54)
					(radius 0.3556)
					(stroke
						(width 0.254)
						(type default)
					)
					(fill
						(type outline)
					)
				)
				(polyline
					(pts
						(xy 10.16 2.54) (xy 8.89 2.54)
					)
					(stroke
						(width 0.254)
						(type default)
					)
					(fill
						(type none)
					)
				)
				(polyline
					(pts
						(xy 10.16 -2.54) (xy 8.89 -2.54)
					)
					(stroke
						(width 0.254)
						(type default)
					)
					(fill
						(type none)
					)
				)
				(pin passive line
					(at 0 0 0)
					(length 2.54)
					(name "~"
						(effects
							(font
								(size 1.27 1.27)
							)
						)
					)
					(number "2"
						(effects
							(font
								(size 1.27 1.27)
							)
						)
					)
				)
				(pin passive line
					(at 12.7 2.54 180)
					(length 2.54)
					(name "~"
						(effects
							(font
								(size 1.27 1.27)
							)
						)
					)
					(number "1"
						(effects
							(font
								(size 1.27 1.27)
							)
						)
					)
				)
				(pin passive line
					(at 12.7 -2.54 180)
					(length 2.54)
					(name "~"
						(effects
							(font
								(size 1.27 1.27)
							)
						)
					)
					(number "3"
						(effects
							(font
								(size 1.27 1.27)
							)
						)
					)
				)
			)
		)
	(symbol "antmicroTVSDiodes:TPD2E009_SOT-9X3"
			(pin_names
				(hide yes)
			)
			(exclude_from_sim no)
			(in_bom yes)
			(on_board yes)
			(property "Reference" "D"
				(at 15.24 0 0)
				(effects
					(font
						(size 1.27 1.27)
						(thickness 0.15)
					)
					(justify left bottom)
				)
			)
			(property "Value" "TPD2E009_SOT-9X3"
				(at 15.24 -2.54 0)
				(effects
					(font
						(size 1.27 1.27)
						(thickness 0.15)
					)
					(justify left bottom)
				)
			)
			(property "Footprint" "antmicro-footprints:SOT-723"
				(at 15.24 -5.08 0)
				(effects
					(font
						(size 1.27 1.27)
						(thickness 0.15)
					)
					(justify left bottom)
					(hide yes)
				)
			)
			(property "Datasheet" "https://www.ti.com/lit/ds/symlink/tpd2e009.pdf?ts=1597910439511&ref_url=https%253A%252F%252Fwww.google.com%252F"
				(at 15.24 -7.62 0)
				(effects
					(font
						(size 1.27 1.27)
						(thickness 0.15)
					)
					(justify left bottom)
					(hide yes)
				)
			)
			(property "Description" "2-Channel ESD Solution for High-Speed (6-Gbps) Differential Interface"
				(at 0 0 0)
				(effects
					(font
						(size 1.27 1.27)
					)
					(hide yes)
				)
			)
			(property "MPN" "TPD2E009DRTR"
				(at 15.24 -10.16 0)
				(effects
					(font
						(size 1.27 1.27)
						(thickness 0.15)
					)
					(justify left bottom)
					(hide yes)
				)
			)
			(property "Manufacturer" "Texas Instruments"
				(at 15.24 -12.7 0)
				(effects
					(font
						(size 1.27 1.27)
						(thickness 0.15)
					)
					(justify left bottom)
					(hide yes)
				)
			)
			(property "Author" "Antmicro"
				(at 15.24 -15.24 0)
				(effects
					(font
						(size 1.27 1.27)
						(thickness 0.15)
					)
					(justify left bottom)
					(hide yes)
				)
			)
			(property "License" "Apache-2.0"
				(at 15.24 -17.78 0)
				(effects
					(font
						(size 1.27 1.27)
						(thickness 0.15)
					)
					(justify left bottom)
					(hide yes)
				)
			)
			(symbol "TPD2E009_SOT-9X3_1_1"
				(rectangle
					(start 2.54 2.54)
					(end 8.89 -7.62)
					(stroke
						(width 0.254)
						(type default)
					)
					(fill
						(type background)
					)
				)
				(polyline
					(pts
						(xy 2.54 0) (xy 7.62 0)
					)
					(stroke
						(width 0.254)
						(type default)
					)
					(fill
						(type background)
					)
				)
				(polyline
					(pts
						(xy 2.54 -2.54) (xy 7.62 -2.54)
					)
					(stroke
						(width 0.254)
						(type default)
					)
					(fill
						(type background)
					)
				)
				(polyline
					(pts
						(xy 4.826 -0.635) (xy 5.08 -0.381) (xy 5.08 0.381) (xy 5.334 0.635)
					)
					(stroke
						(width 0.254)
						(type default)
					)
					(fill
						(type background)
					)
				)
				(polyline
					(pts
						(xy 4.826 -3.175) (xy 5.08 -2.921) (xy 5.08 -2.159) (xy 5.334 -1.905)
					)
					(stroke
						(width 0.254)
						(type default)
					)
					(fill
						(type background)
					)
				)
				(polyline
					(pts
						(xy 5.08 0) (xy 3.81 -0.635) (xy 3.81 0.635) (xy 5.08 0)
					)
					(stroke
						(width 0.254)
						(type default)
					)
					(fill
						(type background)
					)
				)
				(polyline
					(pts
						(xy 5.08 0) (xy 6.35 0.635) (xy 6.35 -0.635) (xy 5.08 0)
					)
					(stroke
						(width 0.254)
						(type default)
					)
					(fill
						(type background)
					)
				)
				(polyline
					(pts
						(xy 5.08 -2.54) (xy 3.81 -3.175) (xy 3.81 -1.905) (xy 5.08 -2.54)
					)
					(stroke
						(width 0.254)
						(type default)
					)
					(fill
						(type background)
					)
				)
				(polyline
					(pts
						(xy 6.35 -1.905) (xy 6.35 -3.175) (xy 5.08 -2.54) (xy 6.35 -1.905)
					)
					(stroke
						(width 0.254)
						(type default)
					)
					(fill
						(type background)
					)
				)
				(circle
					(center 7.62 -2.54)
					(radius 0.254)
					(stroke
						(width 0.254)
						(type default)
					)
					(fill
						(type background)
					)
				)
				(polyline
					(pts
						(xy 7.62 -5.08) (xy 2.54 -5.08)
					)
					(stroke
						(width 0.254)
						(type default)
					)
					(fill
						(type background)
					)
				)
				(polyline
					(pts
						(xy 7.62 -5.08) (xy 7.62 0)
					)
					(stroke
						(width 0.254)
						(type default)
					)
					(fill
						(type background)
					)
				)
				(pin passive line
					(at 0 0 0)
					(length 2.54)
					(name "1"
						(effects
							(font
								(size 1.27 1.27)
							)
						)
					)
					(number "1"
						(effects
							(font
								(size 1.27 1.27)
							)
						)
					)
				)
				(pin passive line
					(at 0 -2.54 0)
					(length 2.54)
					(name "2"
						(effects
							(font
								(size 1.27 1.27)
							)
						)
					)
					(number "2"
						(effects
							(font
								(size 1.27 1.27)
							)
						)
					)
				)
				(pin passive line
					(at 0 -5.08 0)
					(length 2.54)
					(name "3"
						(effects
							(font
								(size 1.27 1.27)
							)
						)
					)
					(number "3"
						(effects
							(font
								(size 1.27 1.27)
							)
						)
					)
				)
			)
		)
	(symbol "antmicroTVSDiodes:TPD6E05U06RVZR"
			(exclude_from_sim no)
			(in_bom yes)
			(on_board yes)
			(property "Reference" "D"
				(at 22.86 0 0)
				(effects
					(font
						(size 1.27 1.27)
						(thickness 0.15)
					)
					(justify left bottom)
				)
			)
			(property "Value" "TPD6E05U06RVZR"
				(at 22.86 -2.54 0)
				(effects
					(font
						(size 1.27 1.27)
						(thickness 0.15)
					)
					(justify left bottom)
				)
			)
			(property "Footprint" "antmicro-footprints:USON-14_3.5X1.3X0.5mm_P0.5mm"
				(at 22.86 -5.08 0)
				(effects
					(font
						(size 1.27 1.27)
						(thickness 0.15)
					)
					(justify left bottom)
					(hide yes)
				)
			)
			(property "Datasheet" "http://www.ti.com/lit/ds/symlink/tpd6e05u06.pdf"
				(at 22.86 -7.62 0)
				(effects
					(font
						(size 1.27 1.27)
						(thickness 0.15)
					)
					(justify left bottom)
					(hide yes)
				)
			)
			(property "Description" ""
				(at 0 0 0)
				(effects
					(font
						(size 1.27 1.27)
					)
					(hide yes)
				)
			)
			(property "MPN" "TPD6E05U06RVZR"
				(at 22.86 -10.16 0)
				(effects
					(font
						(size 1.27 1.27)
						(thickness 0.15)
					)
					(justify left bottom)
					(hide yes)
				)
			)
			(property "Manufacturer" "Texas Instruments"
				(at 22.86 -12.7 0)
				(effects
					(font
						(size 1.27 1.27)
						(thickness 0.15)
					)
					(justify left bottom)
					(hide yes)
				)
			)
			(property "Author" "Antmicro"
				(at 22.86 -15.24 0)
				(effects
					(font
						(size 1.27 1.27)
						(thickness 0.15)
					)
					(justify left bottom)
					(hide yes)
				)
			)
			(property "License" "Apache-2.0"
				(at 22.86 -17.78 0)
				(effects
					(font
						(size 1.27 1.27)
						(thickness 0.15)
					)
					(justify left bottom)
					(hide yes)
				)
			)
			(symbol "TPD6E05U06RVZR_0_0"
				(pin passive line
					(at 0 0 0)
					(length 2.54)
					(hide yes)
					(name "D1+"
						(effects
							(font
								(size 1.27 1.27)
							)
						)
					)
					(number "1"
						(effects
							(font
								(size 1.27 1.27)
							)
						)
					)
				)
				(pin passive line
					(at 0 -2.54 0)
					(length 2.54)
					(hide yes)
					(name "D1-"
						(effects
							(font
								(size 1.27 1.27)
							)
						)
					)
					(number "2"
						(effects
							(font
								(size 1.27 1.27)
							)
						)
					)
				)
				(pin passive line
					(at 0 -7.62 0)
					(length 2.54)
					(hide yes)
					(name "D2+"
						(effects
							(font
								(size 1.27 1.27)
							)
						)
					)
					(number "3"
						(effects
							(font
								(size 1.27 1.27)
							)
						)
					)
				)
				(pin passive line
					(at 0 -10.16 0)
					(length 2.54)
					(hide yes)
					(name "D2-"
						(effects
							(font
								(size 1.27 1.27)
							)
						)
					)
					(number "4"
						(effects
							(font
								(size 1.27 1.27)
							)
						)
					)
				)
				(pin passive line
					(at 0 -15.24 0)
					(length 2.54)
					(hide yes)
					(name "D3+"
						(effects
							(font
								(size 1.27 1.27)
							)
						)
					)
					(number "6"
						(effects
							(font
								(size 1.27 1.27)
							)
						)
					)
				)
				(pin passive line
					(at 0 -17.78 0)
					(length 2.54)
					(hide yes)
					(name "D3-"
						(effects
							(font
								(size 1.27 1.27)
							)
						)
					)
					(number "7"
						(effects
							(font
								(size 1.27 1.27)
							)
						)
					)
				)
			)
			(symbol "TPD6E05U06RVZR_0_1"
				(rectangle
					(start 2.54 2.54)
					(end 8.89 -25.4)
					(stroke
						(width 0)
						(type default)
					)
					(fill
						(type background)
					)
				)
			)
			(symbol "TPD6E05U06RVZR_1_1"
				(pin passive line
					(at 0 0 0)
					(length 2.54)
					(name "D1+"
						(effects
							(font
								(size 1.27 1.27)
							)
						)
					)
					(number "14"
						(effects
							(font
								(size 1.27 1.27)
							)
						)
					)
				)
				(pin passive line
					(at 0 -2.54 0)
					(length 2.54)
					(name "D1-"
						(effects
							(font
								(size 1.27 1.27)
							)
						)
					)
					(number "13"
						(effects
							(font
								(size 1.27 1.27)
							)
						)
					)
				)
				(pin passive line
					(at 0 -7.62 0)
					(length 2.54)
					(name "D2+"
						(effects
							(font
								(size 1.27 1.27)
							)
						)
					)
					(number "12"
						(effects
							(font
								(size 1.27 1.27)
							)
						)
					)
				)
				(pin passive line
					(at 0 -10.16 0)
					(length 2.54)
					(name "D2-"
						(effects
							(font
								(size 1.27 1.27)
							)
						)
					)
					(number "11"
						(effects
							(font
								(size 1.27 1.27)
							)
						)
					)
				)
				(pin passive line
					(at 0 -15.24 0)
					(length 2.54)
					(name "D3+"
						(effects
							(font
								(size 1.27 1.27)
							)
						)
					)
					(number "9"
						(effects
							(font
								(size 1.27 1.27)
							)
						)
					)
				)
				(pin passive line
					(at 0 -17.78 0)
					(length 2.54)
					(name "D3-"
						(effects
							(font
								(size 1.27 1.27)
							)
						)
					)
					(number "8"
						(effects
							(font
								(size 1.27 1.27)
							)
						)
					)
				)
				(pin passive line
					(at 0 -22.86 0)
					(length 2.54)
					(hide yes)
					(name "GND"
						(effects
							(font
								(size 1.27 1.27)
							)
						)
					)
					(number "10"
						(effects
							(font
								(size 1.27 1.27)
							)
						)
					)
				)
				(pin power_in line
					(at 0 -22.86 0)
					(length 2.54)
					(name "GND"
						(effects
							(font
								(size 1.27 1.27)
							)
						)
					)
					(number "5"
						(effects
							(font
								(size 1.27 1.27)
							)
						)
					)
				)
			)
		)
	(symbol "antmicroTVSDiodes:TPD8S009DSMR"
			(exclude_from_sim no)
			(in_bom yes)
			(on_board yes)
			(property "Reference" "U"
				(at 30.48 -2.54 0)
				(effects
					(font
						(size 1.27 1.27)
						(thickness 0.15)
					)
					(justify left bottom)
				)
			)
			(property "Value" "TPD8S009DSMR"
				(at 30.48 -5.08 0)
				(effects
					(font
						(size 1.27 1.27)
						(thickness 0.15)
					)
					(justify left bottom)
				)
			)
			(property "Footprint" "antmicro-footprints:R-PDSO-N15"
				(at 30.48 -7.62 0)
				(effects
					(font
						(size 1.27 1.27)
						(thickness 0.15)
					)
					(justify left bottom)
					(hide yes)
				)
			)
			(property "Datasheet" "https://www.ti.com/lit/ds/symlink/tpd8s009.pdf?ts=1679406571326&ref_url=https%253A%252F%252Fwww.ti.com%252Fproduct%252FTPD8S009%252Fpart-details%252FTPD8S009DSMR"
				(at 30.48 -10.16 0)
				(effects
					(font
						(size 1.27 1.27)
						(thickness 0.15)
					)
					(justify left bottom)
					(hide yes)
				)
			)
			(property "Description" ""
				(at 0 0 0)
				(effects
					(font
						(size 1.27 1.27)
					)
					(hide yes)
				)
			)
			(property "MPN" "TPD8S009DSMR"
				(at 30.48 -12.7 0)
				(effects
					(font
						(size 1.27 1.27)
						(thickness 0.15)
					)
					(justify left bottom)
					(hide yes)
				)
			)
			(property "Manufacturer" "Texas Instruments"
				(at 30.48 -15.24 0)
				(effects
					(font
						(size 1.27 1.27)
						(thickness 0.15)
					)
					(justify left bottom)
					(hide yes)
				)
			)
			(property "Author" "Antmicro"
				(at 30.48 -17.78 0)
				(effects
					(font
						(size 1.27 1.27)
						(thickness 0.15)
					)
					(justify left bottom)
					(hide yes)
				)
			)
			(property "License" "Apache-2.0"
				(at 30.48 -20.32 0)
				(effects
					(font
						(size 1.27 1.27)
						(thickness 0.15)
					)
					(justify left bottom)
					(hide yes)
				)
			)
			(symbol "TPD8S009DSMR_1_1"
				(rectangle
					(start 2.54 -20.32)
					(end 13.97 2.54)
					(stroke
						(width 0.254)
						(type default)
					)
					(fill
						(type background)
					)
				)
				(pin passive line
					(at 0 0 0)
					(length 2.54)
					(name "D0+"
						(effects
							(font
								(size 1.27 1.27)
							)
						)
					)
					(number "1"
						(effects
							(font
								(size 1.27 1.27)
							)
						)
					)
				)
				(pin passive line
					(at 0 -2.54 0)
					(length 2.54)
					(name "D0-"
						(effects
							(font
								(size 1.27 1.27)
							)
						)
					)
					(number "3"
						(effects
							(font
								(size 1.27 1.27)
							)
						)
					)
				)
				(pin passive line
					(at 0 -5.08 0)
					(length 2.54)
					(name "D1+"
						(effects
							(font
								(size 1.27 1.27)
							)
						)
					)
					(number "4"
						(effects
							(font
								(size 1.27 1.27)
							)
						)
					)
				)
				(pin passive line
					(at 0 -7.62 0)
					(length 2.54)
					(name "D1-"
						(effects
							(font
								(size 1.27 1.27)
							)
						)
					)
					(number "6"
						(effects
							(font
								(size 1.27 1.27)
							)
						)
					)
				)
				(pin passive line
					(at 0 -10.16 0)
					(length 2.54)
					(name "D2+"
						(effects
							(font
								(size 1.27 1.27)
							)
						)
					)
					(number "7"
						(effects
							(font
								(size 1.27 1.27)
							)
						)
					)
				)
				(pin passive line
					(at 0 -12.7 0)
					(length 2.54)
					(name "D2-"
						(effects
							(font
								(size 1.27 1.27)
							)
						)
					)
					(number "9"
						(effects
							(font
								(size 1.27 1.27)
							)
						)
					)
				)
				(pin passive line
					(at 0 -15.24 0)
					(length 2.54)
					(name "D3+"
						(effects
							(font
								(size 1.27 1.27)
							)
						)
					)
					(number "10"
						(effects
							(font
								(size 1.27 1.27)
							)
						)
					)
				)
				(pin passive line
					(at 0 -17.78 0)
					(length 2.54)
					(name "D3-"
						(effects
							(font
								(size 1.27 1.27)
							)
						)
					)
					(number "12"
						(effects
							(font
								(size 1.27 1.27)
							)
						)
					)
				)
				(pin no_connect line
					(at 13.97 -15.24 180)
					(length 2.54)
					(hide yes)
					(name "NC"
						(effects
							(font
								(size 1.27 1.27)
							)
						)
					)
					(number "14"
						(effects
							(font
								(size 1.27 1.27)
							)
						)
					)
				)
				(pin power_in line
					(at 16.51 0 180)
					(length 2.54)
					(name "VCC"
						(effects
							(font
								(size 1.27 1.27)
							)
						)
					)
					(number "13"
						(effects
							(font
								(size 1.27 1.27)
							)
						)
					)
				)
				(pin passive line
					(at 16.51 0 180)
					(length 2.54)
					(hide yes)
					(name "VCC"
						(effects
							(font
								(size 1.27 1.27)
							)
						)
					)
					(number "15"
						(effects
							(font
								(size 1.27 1.27)
							)
						)
					)
				)
				(pin passive line
					(at 16.51 -17.78 180)
					(length 2.54)
					(hide yes)
					(name "GND"
						(effects
							(font
								(size 1.27 1.27)
							)
						)
					)
					(number "11"
						(effects
							(font
								(size 1.27 1.27)
							)
						)
					)
				)
				(pin passive line
					(at 16.51 -17.78 180)
					(length 2.54)
					(name "GND"
						(effects
							(font
								(size 1.27 1.27)
							)
						)
					)
					(number "2"
						(effects
							(font
								(size 1.27 1.27)
							)
						)
					)
				)
				(pin passive line
					(at 16.51 -17.78 180)
					(length 2.54)
					(hide yes)
					(name "GND"
						(effects
							(font
								(size 1.27 1.27)
							)
						)
					)
					(number "5"
						(effects
							(font
								(size 1.27 1.27)
							)
						)
					)
				)
				(pin passive line
					(at 16.51 -17.78 180)
					(length 2.54)
					(hide yes)
					(name "GND"
						(effects
							(font
								(size 1.27 1.27)
							)
						)
					)
					(number "8"
						(effects
							(font
								(size 1.27 1.27)
							)
						)
					)
				)
				(pin passive line
					(at 16.51 -17.78 180)
					(length 2.54)
					(hide yes)
					(name "GND"
						(effects
							(font
								(size 1.27 1.27)
							)
						)
					)
					(number "8"
						(effects
							(font
								(size 1.27 1.27)
							)
						)
					)
				)
			)
		)
	(symbol "antmicroTestPoints:TP_1mm_SMD"
			(pin_numbers
				(hide yes)
			)
			(pin_names
				(hide yes)
			)
			(exclude_from_sim no)
			(in_bom yes)
			(on_board yes)
			(property "Reference" "TP"
				(at 15.24 -5.08 0)
				(effects
					(font
						(size 1.27 1.27)
						(thickness 0.15)
					)
					(justify left bottom)
				)
			)
			(property "Value" "TP_1mm_SMD"
				(at 15.24 -7.62 0)
				(effects
					(font
						(size 1.27 1.27)
						(thickness 0.15)
					)
					(justify left bottom)
					(hide yes)
				)
			)
			(property "Footprint" "antmicro-footprints:TP_SMD_1mm"
				(at 15.24 -10.16 0)
				(effects
					(font
						(size 1.27 1.27)
						(thickness 0.15)
					)
					(justify left bottom)
					(hide yes)
				)
			)
			(property "Datasheet" ""
				(at 15.24 -12.7 0)
				(effects
					(font
						(size 1.27 1.27)
						(thickness 0.15)
					)
					(justify left bottom)
					(hide yes)
				)
			)
			(property "Description" "Test Point 1mm"
				(at 0 0 0)
				(effects
					(font
						(size 1.27 1.27)
					)
					(hide yes)
				)
			)
			(property "MPN" ""
				(at 0 0 0)
				(effects
					(font
						(size 1.27 1.27)
					)
					(hide yes)
				)
			)
			(property "Manufacturer" ""
				(at 0 0 0)
				(effects
					(font
						(size 1.27 1.27)
					)
					(hide yes)
				)
			)
			(property "Author" "Antmicro"
				(at 15.24 -15.24 0)
				(effects
					(font
						(size 1.27 1.27)
						(thickness 0.15)
					)
					(justify left bottom)
					(hide yes)
				)
			)
			(property "License" "Apache-2.0"
				(at 15.24 -17.78 0)
				(effects
					(font
						(size 1.27 1.27)
						(thickness 0.15)
					)
					(justify left bottom)
					(hide yes)
				)
			)
			(symbol "TP_1mm_SMD_1_1"
				(circle
					(center 3.175 0)
					(radius 0.635)
					(stroke
						(width 0.254)
						(type default)
					)
					(fill
						(type none)
					)
				)
				(pin passive line
					(at 0 0 0)
					(length 2.54)
					(name "1"
						(effects
							(font
								(size 1.27 1.27)
							)
						)
					)
					(number "1"
						(effects
							(font
								(size 1.27 1.27)
							)
						)
					)
				)
			)
		)
	(symbol "antmicroTransistorsFETsMOSFETsSingle:BSS123"
			(pin_names
				(offset 0)
			)
			(exclude_from_sim no)
			(in_bom yes)
			(on_board yes)
			(property "Reference" "Q"
				(at 22.86 -6.35 0)
				(effects
					(font
						(size 1.27 1.27)
						(thickness 0.15)
					)
					(justify left bottom)
				)
			)
			(property "Value" "BSS123"
				(at 22.86 -8.89 0)
				(effects
					(font
						(size 1.27 1.27)
						(thickness 0.15)
					)
					(justify left bottom)
				)
			)
			(property "Footprint" "antmicro-footprints:SOT-23-3"
				(at 22.86 -11.43 0)
				(effects
					(font
						(size 1.27 1.27)
						(thickness 0.15)
					)
					(justify left bottom)
					(hide yes)
				)
			)
			(property "Datasheet" "https://www.onsemi.com/pub/Collateral/BSS123-D.PDF"
				(at 22.86 -13.97 0)
				(effects
					(font
						(size 1.27 1.27)
						(thickness 0.15)
					)
					(justify left bottom)
					(hide yes)
				)
			)
			(property "Description" ""
				(at 0 0 0)
				(effects
					(font
						(size 1.27 1.27)
					)
					(hide yes)
				)
			)
			(property "MPN" "BSS123"
				(at 22.86 -16.51 0)
				(effects
					(font
						(size 1.27 1.27)
						(thickness 0.15)
					)
					(justify left bottom)
					(hide yes)
				)
			)
			(property "Manufacturer" "ON Semiconductor"
				(at 22.86 -19.05 0)
				(effects
					(font
						(size 1.27 1.27)
						(thickness 0.15)
					)
					(justify left bottom)
					(hide yes)
				)
			)
			(property "Author" "Antmicro"
				(at 22.86 -21.59 0)
				(effects
					(font
						(size 1.27 1.27)
						(thickness 0.15)
					)
					(justify left bottom)
					(hide yes)
				)
			)
			(property "License" "Apache-2.0"
				(at 22.86 -24.13 0)
				(effects
					(font
						(size 1.27 1.27)
						(thickness 0.15)
					)
					(justify left bottom)
					(hide yes)
				)
			)
			(symbol "BSS123_1_1"
				(polyline
					(pts
						(xy 2.54 0) (xy 4.572 0) (xy 4.572 3.937)
					)
					(stroke
						(width 0.254)
						(type default)
					)
					(fill
						(type none)
					)
				)
				(polyline
					(pts
						(xy 5.08 4.445) (xy 5.08 3.429)
					)
					(stroke
						(width 0.254)
						(type default)
					)
					(fill
						(type background)
					)
				)
				(polyline
					(pts
						(xy 5.08 2.54) (xy 5.08 3.048)
					)
					(stroke
						(width 0.254)
						(type default)
					)
					(fill
						(type background)
					)
				)
				(polyline
					(pts
						(xy 5.08 2.54) (xy 5.08 2.032)
					)
					(stroke
						(width 0.254)
						(type default)
					)
					(fill
						(type background)
					)
				)
				(polyline
					(pts
						(xy 5.08 2.54) (xy 5.842 3.048) (xy 5.842 2.032) (xy 5.08 2.54)
					)
					(stroke
						(width 0.254)
						(type default)
					)
					(fill
						(type outline)
					)
				)
				(polyline
					(pts
						(xy 5.08 1.143) (xy 5.08 1.651)
					)
					(stroke
						(width 0.254)
						(type default)
					)
					(fill
						(type background)
					)
				)
				(polyline
					(pts
						(xy 5.08 1.143) (xy 5.08 0.635)
					)
					(stroke
						(width 0.254)
						(type default)
					)
					(fill
						(type background)
					)
				)
				(circle
					(center 6.35 2.54)
					(radius 3.302)
					(stroke
						(width 0.254)
						(type default)
					)
					(fill
						(type background)
					)
				)
				(polyline
					(pts
						(xy 7.493 0.635) (xy 8.636 0.635) (xy 8.636 3.937) (xy 8.636 4.445) (xy 7.493 4.445)
					)
					(stroke
						(width 0.254)
						(type default)
					)
					(fill
						(type background)
					)
				)
				(polyline
					(pts
						(xy 7.62 5.08) (xy 7.62 3.937) (xy 5.08 3.937)
					)
					(stroke
						(width 0.254)
						(type default)
					)
					(fill
						(type background)
					)
				)
				(circle
					(center 7.62 4.445)
					(radius 0.127)
					(stroke
						(width 0.254)
						(type default)
					)
					(fill
						(type background)
					)
				)
				(polyline
					(pts
						(xy 7.62 1.143) (xy 5.08 1.143)
					)
					(stroke
						(width 0.254)
						(type default)
					)
					(fill
						(type background)
					)
				)
				(circle
					(center 7.62 1.143)
					(radius 0.127)
					(stroke
						(width 0.254)
						(type default)
					)
					(fill
						(type background)
					)
				)
				(circle
					(center 7.62 0.635)
					(radius 0.127)
					(stroke
						(width 0.254)
						(type default)
					)
					(fill
						(type background)
					)
				)
				(polyline
					(pts
						(xy 7.62 0) (xy 7.62 2.54) (xy 5.08 2.54)
					)
					(stroke
						(width 0.254)
						(type default)
					)
					(fill
						(type background)
					)
				)
				(polyline
					(pts
						(xy 8.636 3.048) (xy 8.128 2.286) (xy 9.144 2.286) (xy 8.636 3.048)
					)
					(stroke
						(width 0.254)
						(type default)
					)
					(fill
						(type outline)
					)
				)
				(polyline
					(pts
						(xy 9.144 3.048) (xy 8.128 3.048)
					)
					(stroke
						(width 0.254)
						(type default)
					)
					(fill
						(type background)
					)
				)
				(pin bidirectional line
					(at 0 0 0)
					(length 2.54)
					(name "G"
						(effects
							(font
								(size 1.27 1.27)
							)
						)
					)
					(number "1"
						(effects
							(font
								(size 1.27 1.27)
							)
						)
					)
				)
				(pin bidirectional line
					(at 7.62 7.62 270)
					(length 2.54)
					(name "D"
						(effects
							(font
								(size 1.27 1.27)
							)
						)
					)
					(number "3"
						(effects
							(font
								(size 1.27 1.27)
							)
						)
					)
				)
				(pin bidirectional line
					(at 7.62 -2.54 90)
					(length 2.54)
					(name "S"
						(effects
							(font
								(size 1.27 1.27)
							)
						)
					)
					(number "2"
						(effects
							(font
								(size 1.27 1.27)
							)
						)
					)
				)
			)
		)
	(symbol "antmicroTransistorsFETsMOSFETsSingle:BSS138PW"
			(pin_names
				(offset 0)
			)
			(exclude_from_sim no)
			(in_bom yes)
			(on_board yes)
			(property "Reference" "Q"
				(at 3.81 -6.35 0)
				(effects
					(font
						(size 1.27 1.27)
						(thickness 0.15)
					)
					(justify left bottom)
				)
			)
			(property "Value" "BSS138PW"
				(at 22.86 -8.89 0)
				(effects
					(font
						(size 1.27 1.27)
						(thickness 0.15)
					)
					(justify left bottom)
				)
			)
			(property "Footprint" "antmicro-footprints:SC70-3"
				(at 22.86 -11.43 0)
				(effects
					(font
						(size 1.27 1.27)
						(thickness 0.15)
					)
					(justify left bottom)
					(hide yes)
				)
			)
			(property "Datasheet" "https://assets.nexperia.com/documents/data-sheet/BSS138PW.pdf"
				(at 22.86 -13.97 0)
				(effects
					(font
						(size 1.27 1.27)
						(thickness 0.15)
					)
					(justify left bottom)
					(hide yes)
				)
			)
			(property "Description" "60 V, 320 mA N-channel enhancement mode Trench MOSFET, SC-70-3 aka SOT-323 package"
				(at 0 0 0)
				(effects
					(font
						(size 1.27 1.27)
					)
					(hide yes)
				)
			)
			(property "MPN" "BSS138PW"
				(at 22.86 -16.51 0)
				(effects
					(font
						(size 1.27 1.27)
						(thickness 0.15)
					)
					(justify left bottom)
					(hide yes)
				)
			)
			(property "Manufacturer" "Nexperia"
				(at 22.86 -19.05 0)
				(effects
					(font
						(size 1.27 1.27)
						(thickness 0.15)
					)
					(justify left bottom)
					(hide yes)
				)
			)
			(property "Author" "Antmicro"
				(at 22.86 -21.59 0)
				(effects
					(font
						(size 1.27 1.27)
						(thickness 0.15)
					)
					(justify left bottom)
					(hide yes)
				)
			)
			(property "License" "Apache-2.0"
				(at 22.86 -24.13 0)
				(effects
					(font
						(size 1.27 1.27)
						(thickness 0.15)
					)
					(justify left bottom)
					(hide yes)
				)
			)
			(property "ki_keywords" "n-channel enhancement mosfet sc70 sc-70 sot-323 sot323"
				(at 0 0 0)
				(effects
					(font
						(size 1.27 1.27)
					)
					(hide yes)
				)
			)
			(symbol "BSS138PW_1_1"
				(polyline
					(pts
						(xy 2.54 0) (xy 4.572 0) (xy 4.572 3.937)
					)
					(stroke
						(width 0.254)
						(type default)
					)
					(fill
						(type none)
					)
				)
				(polyline
					(pts
						(xy 5.08 4.445) (xy 5.08 3.429)
					)
					(stroke
						(width 0.254)
						(type default)
					)
					(fill
						(type background)
					)
				)
				(polyline
					(pts
						(xy 5.08 2.54) (xy 5.08 3.048)
					)
					(stroke
						(width 0.254)
						(type default)
					)
					(fill
						(type background)
					)
				)
				(polyline
					(pts
						(xy 5.08 2.54) (xy 5.08 2.032)
					)
					(stroke
						(width 0.254)
						(type default)
					)
					(fill
						(type background)
					)
				)
				(polyline
					(pts
						(xy 5.08 2.54) (xy 5.842 3.048) (xy 5.842 2.032) (xy 5.08 2.54)
					)
					(stroke
						(width 0.254)
						(type default)
					)
					(fill
						(type outline)
					)
				)
				(polyline
					(pts
						(xy 5.08 1.143) (xy 5.08 1.651)
					)
					(stroke
						(width 0.254)
						(type default)
					)
					(fill
						(type background)
					)
				)
				(polyline
					(pts
						(xy 5.08 1.143) (xy 5.08 0.635)
					)
					(stroke
						(width 0.254)
						(type default)
					)
					(fill
						(type background)
					)
				)
				(circle
					(center 6.35 2.54)
					(radius 3.302)
					(stroke
						(width 0.254)
						(type default)
					)
					(fill
						(type background)
					)
				)
				(polyline
					(pts
						(xy 7.493 0.635) (xy 8.636 0.635) (xy 8.636 3.937) (xy 8.636 4.445) (xy 7.493 4.445)
					)
					(stroke
						(width 0.254)
						(type default)
					)
					(fill
						(type background)
					)
				)
				(polyline
					(pts
						(xy 7.62 6.35) (xy 7.62 3.937) (xy 5.08 3.937)
					)
					(stroke
						(width 0.254)
						(type default)
					)
					(fill
						(type background)
					)
				)
				(circle
					(center 7.62 4.445)
					(radius 0.127)
					(stroke
						(width 0.254)
						(type default)
					)
					(fill
						(type background)
					)
				)
				(polyline
					(pts
						(xy 7.62 1.143) (xy 5.08 1.143)
					)
					(stroke
						(width 0.254)
						(type default)
					)
					(fill
						(type background)
					)
				)
				(circle
					(center 7.62 1.143)
					(radius 0.127)
					(stroke
						(width 0.254)
						(type default)
					)
					(fill
						(type background)
					)
				)
				(circle
					(center 7.62 0.635)
					(radius 0.127)
					(stroke
						(width 0.254)
						(type default)
					)
					(fill
						(type background)
					)
				)
				(polyline
					(pts
						(xy 7.62 -1.27) (xy 7.62 2.54) (xy 5.08 2.54)
					)
					(stroke
						(width 0.254)
						(type default)
					)
					(fill
						(type background)
					)
				)
				(polyline
					(pts
						(xy 8.636 3.048) (xy 8.128 2.286) (xy 9.144 2.286) (xy 8.636 3.048)
					)
					(stroke
						(width 0.254)
						(type default)
					)
					(fill
						(type outline)
					)
				)
				(polyline
					(pts
						(xy 9.144 3.048) (xy 8.128 3.048)
					)
					(stroke
						(width 0.254)
						(type default)
					)
					(fill
						(type background)
					)
				)
				(pin bidirectional line
					(at 0 0 0)
					(length 2.54)
					(name "G"
						(effects
							(font
								(size 1.27 1.27)
							)
						)
					)
					(number "1"
						(effects
							(font
								(size 1.27 1.27)
							)
						)
					)
				)
				(pin bidirectional line
					(at 7.62 8.89 270)
					(length 2.54)
					(name "D"
						(effects
							(font
								(size 1.27 1.27)
							)
						)
					)
					(number "3"
						(effects
							(font
								(size 1.27 1.27)
							)
						)
					)
				)
				(pin bidirectional line
					(at 7.62 -3.81 90)
					(length 2.54)
					(name "S"
						(effects
							(font
								(size 1.27 1.27)
							)
						)
					)
					(number "2"
						(effects
							(font
								(size 1.27 1.27)
							)
						)
					)
				)
			)
		)
	(symbol "antmicroTransistorsFETsMOSFETsSingle:DMG1012T-7"
			(pin_names
				(offset 0)
				(hide yes)
			)
			(exclude_from_sim no)
			(in_bom yes)
			(on_board yes)
			(property "Reference" "Q"
				(at 10.16 3.81 0)
				(effects
					(font
						(size 1.27 1.27)
						(thickness 0.15)
					)
					(justify left bottom)
				)
			)
			(property "Value" "DMG1012T-7"
				(at 10.16 -3.81 0)
				(effects
					(font
						(size 1.27 1.27)
						(thickness 0.15)
					)
					(justify left bottom)
					(hide yes)
				)
			)
			(property "Footprint" "antmicro-footprints:SOT-523"
				(at 10.16 -6.35 0)
				(effects
					(font
						(size 1.27 1.27)
						(thickness 0.15)
					)
					(justify left bottom)
					(hide yes)
				)
			)
			(property "Datasheet" "https://www.diodes.com/assets/Datasheets/ds31783.pdf"
				(at 10.16 -8.89 0)
				(effects
					(font
						(size 1.27 1.27)
						(thickness 0.15)
					)
					(justify left bottom)
					(hide yes)
				)
			)
			(property "Description" ""
				(at 0 0 0)
				(effects
					(font
						(size 1.27 1.27)
					)
					(hide yes)
				)
			)
			(property "MPN" "DMG1012T-7"
				(at 10.16 1.27 0)
				(effects
					(font
						(size 1.27 1.27)
						(thickness 0.15)
					)
					(justify left bottom)
				)
			)
			(property "Manufacturer" "Diodes Incorporated"
				(at 10.16 -1.27 0)
				(effects
					(font
						(size 1.27 1.27)
						(thickness 0.15)
					)
					(justify left bottom)
					(hide yes)
				)
			)
			(property "Author" "Antmicro"
				(at 10.16 -11.43 0)
				(effects
					(font
						(size 1.27 1.27)
						(thickness 0.15)
					)
					(justify left bottom)
					(hide yes)
				)
			)
			(property "License" "Apache-2.0"
				(at 10.16 -13.97 0)
				(effects
					(font
						(size 1.27 1.27)
						(thickness 0.15)
					)
					(justify left bottom)
					(hide yes)
				)
			)
			(symbol "DMG1012T-7_1_1"
				(polyline
					(pts
						(xy 1.27 0) (xy 3.302 0) (xy 3.302 3.937)
					)
					(stroke
						(width 0.254)
						(type default)
					)
					(fill
						(type none)
					)
				)
				(polyline
					(pts
						(xy 3.81 4.445) (xy 3.81 3.429)
					)
					(stroke
						(width 0.254)
						(type default)
					)
					(fill
						(type background)
					)
				)
				(polyline
					(pts
						(xy 3.81 2.54) (xy 3.81 3.048)
					)
					(stroke
						(width 0.254)
						(type default)
					)
					(fill
						(type background)
					)
				)
				(polyline
					(pts
						(xy 3.81 2.54) (xy 3.81 2.032)
					)
					(stroke
						(width 0.254)
						(type default)
					)
					(fill
						(type background)
					)
				)
				(polyline
					(pts
						(xy 3.81 2.54) (xy 4.572 3.048) (xy 4.572 2.032) (xy 3.81 2.54)
					)
					(stroke
						(width 0.254)
						(type default)
					)
					(fill
						(type outline)
					)
				)
				(polyline
					(pts
						(xy 3.81 1.143) (xy 3.81 1.651)
					)
					(stroke
						(width 0.254)
						(type default)
					)
					(fill
						(type background)
					)
				)
				(polyline
					(pts
						(xy 3.81 1.143) (xy 3.81 0.635)
					)
					(stroke
						(width 0.254)
						(type default)
					)
					(fill
						(type background)
					)
				)
				(circle
					(center 5.08 2.54)
					(radius 3.302)
					(stroke
						(width 0.254)
						(type default)
					)
					(fill
						(type background)
					)
				)
				(polyline
					(pts
						(xy 6.223 0.635) (xy 7.366 0.635) (xy 7.366 3.937) (xy 7.366 4.445) (xy 6.223 4.445)
					)
					(stroke
						(width 0.254)
						(type default)
					)
					(fill
						(type none)
					)
				)
				(polyline
					(pts
						(xy 6.35 6.35) (xy 6.35 3.937) (xy 3.81 3.937)
					)
					(stroke
						(width 0.254)
						(type default)
					)
					(fill
						(type none)
					)
				)
				(circle
					(center 6.35 4.445)
					(radius 0.127)
					(stroke
						(width 0.254)
						(type default)
					)
					(fill
						(type background)
					)
				)
				(polyline
					(pts
						(xy 6.35 1.143) (xy 3.81 1.143)
					)
					(stroke
						(width 0.254)
						(type default)
					)
					(fill
						(type background)
					)
				)
				(circle
					(center 6.35 1.143)
					(radius 0.127)
					(stroke
						(width 0.254)
						(type default)
					)
					(fill
						(type background)
					)
				)
				(circle
					(center 6.35 0.635)
					(radius 0.127)
					(stroke
						(width 0.254)
						(type default)
					)
					(fill
						(type background)
					)
				)
				(polyline
					(pts
						(xy 6.35 -1.27) (xy 6.35 2.54) (xy 3.81 2.54)
					)
					(stroke
						(width 0.254)
						(type default)
					)
					(fill
						(type none)
					)
				)
				(polyline
					(pts
						(xy 7.366 3.048) (xy 6.858 2.286) (xy 7.874 2.286) (xy 7.366 3.048)
					)
					(stroke
						(width 0.254)
						(type default)
					)
					(fill
						(type outline)
					)
				)
				(polyline
					(pts
						(xy 7.874 3.048) (xy 6.858 3.048)
					)
					(stroke
						(width 0.254)
						(type default)
					)
					(fill
						(type background)
					)
				)
				(pin bidirectional line
					(at 0 0 0)
					(length 2.54)
					(name "G"
						(effects
							(font
								(size 1.27 1.27)
							)
						)
					)
					(number "1"
						(effects
							(font
								(size 1.27 1.27)
							)
						)
					)
				)
				(pin bidirectional line
					(at 6.35 7.62 270)
					(length 2.54)
					(name "D"
						(effects
							(font
								(size 1.27 1.27)
							)
						)
					)
					(number "3"
						(effects
							(font
								(size 1.27 1.27)
							)
						)
					)
				)
				(pin bidirectional line
					(at 6.35 -2.54 90)
					(length 2.54)
					(name "S"
						(effects
							(font
								(size 1.27 1.27)
							)
						)
					)
					(number "2"
						(effects
							(font
								(size 1.27 1.27)
							)
						)
					)
				)
			)
		)
	(symbol "antmicroTransistorsFETsMOSFETsSingle:SQS401EN-T1_BE3"
			(pin_names
				(offset 0)
				(hide yes)
			)
			(exclude_from_sim no)
			(in_bom yes)
			(on_board yes)
			(property "Reference" "Q"
				(at 15.24 -5.08 0)
				(effects
					(font
						(size 1.27 1.27)
						(thickness 0.15)
					)
					(justify left bottom)
				)
			)
			(property "Value" "SQS401EN-T1_BE3"
				(at 15.24 -10.16 0)
				(effects
					(font
						(size 1.27 1.27)
						(thickness 0.15)
					)
					(justify left bottom)
					(hide yes)
				)
			)
			(property "Footprint" "antmicro-footprints:Vishay_PowerPAK_1212-8_Single"
				(at 15.24 -12.7 0)
				(effects
					(font
						(size 1.27 1.27)
						(thickness 0.15)
					)
					(justify left bottom)
					(hide yes)
				)
			)
			(property "Datasheet" "https://www.vishay.com/docs/65529/sqs401en.pdf"
				(at 15.24 -15.24 0)
				(effects
					(font
						(size 1.27 1.27)
						(thickness 0.15)
					)
					(justify left bottom)
					(hide yes)
				)
			)
			(property "Description" "MOSFET P-CHANNEL 40V (D-S), 16 A, PowerPAK 1212-8 Single"
				(at 0 0 0)
				(effects
					(font
						(size 1.27 1.27)
					)
					(hide yes)
				)
			)
			(property "MPN" "SQS401EN-T1_BE3"
				(at 15.24 -7.62 0)
				(effects
					(font
						(size 1.27 1.27)
						(thickness 0.15)
					)
					(justify left bottom)
				)
			)
			(property "Manufacturer" "Vishay"
				(at 15.24 -17.78 0)
				(effects
					(font
						(size 1.27 1.27)
						(thickness 0.15)
					)
					(justify left bottom)
					(hide yes)
				)
			)
			(property "Author" "Antmicro"
				(at 15.24 -20.32 0)
				(effects
					(font
						(size 1.27 1.27)
						(thickness 0.15)
					)
					(justify left bottom)
					(hide yes)
				)
			)
			(property "License" "Apache-2.0"
				(at 15.24 -22.86 0)
				(effects
					(font
						(size 1.27 1.27)
						(thickness 0.15)
					)
					(justify left bottom)
					(hide yes)
				)
			)
			(symbol "SQS401EN-T1_BE3_1_1"
				(polyline
					(pts
						(xy 1.27 0) (xy 3.302 0) (xy 3.302 3.937)
					)
					(stroke
						(width 0.254)
						(type default)
					)
					(fill
						(type none)
					)
				)
				(polyline
					(pts
						(xy 3.81 4.445) (xy 3.81 3.429)
					)
					(stroke
						(width 0.254)
						(type default)
					)
					(fill
						(type background)
					)
				)
				(polyline
					(pts
						(xy 3.81 2.54) (xy 3.81 3.048)
					)
					(stroke
						(width 0.254)
						(type default)
					)
					(fill
						(type background)
					)
				)
				(polyline
					(pts
						(xy 3.81 2.54) (xy 3.81 2.032)
					)
					(stroke
						(width 0.254)
						(type default)
					)
					(fill
						(type background)
					)
				)
				(polyline
					(pts
						(xy 3.81 1.143) (xy 3.81 1.651)
					)
					(stroke
						(width 0.254)
						(type default)
					)
					(fill
						(type background)
					)
				)
				(polyline
					(pts
						(xy 3.81 1.143) (xy 3.81 0.635)
					)
					(stroke
						(width 0.254)
						(type default)
					)
					(fill
						(type background)
					)
				)
				(circle
					(center 5.08 2.54)
					(radius 3.302)
					(stroke
						(width 0.254)
						(type default)
					)
					(fill
						(type background)
					)
				)
				(polyline
					(pts
						(xy 6.096 2.54) (xy 5.334 2.032) (xy 5.334 3.048) (xy 6.096 2.54)
					)
					(stroke
						(width 0.254)
						(type default)
					)
					(fill
						(type outline)
					)
				)
				(polyline
					(pts
						(xy 6.223 0.635) (xy 7.366 0.635) (xy 7.366 3.937) (xy 7.366 4.445) (xy 6.223 4.445)
					)
					(stroke
						(width 0.254)
						(type default)
					)
					(fill
						(type none)
					)
				)
				(polyline
					(pts
						(xy 6.35 6.35) (xy 6.35 3.937) (xy 3.81 3.937)
					)
					(stroke
						(width 0.254)
						(type default)
					)
					(fill
						(type none)
					)
				)
				(circle
					(center 6.35 4.445)
					(radius 0.127)
					(stroke
						(width 0.254)
						(type default)
					)
					(fill
						(type background)
					)
				)
				(polyline
					(pts
						(xy 6.35 1.143) (xy 3.81 1.143)
					)
					(stroke
						(width 0.254)
						(type default)
					)
					(fill
						(type background)
					)
				)
				(circle
					(center 6.35 1.143)
					(radius 0.127)
					(stroke
						(width 0.254)
						(type default)
					)
					(fill
						(type background)
					)
				)
				(circle
					(center 6.35 0.635)
					(radius 0.127)
					(stroke
						(width 0.254)
						(type default)
					)
					(fill
						(type background)
					)
				)
				(polyline
					(pts
						(xy 6.35 -1.27) (xy 6.35 2.54) (xy 3.81 2.54)
					)
					(stroke
						(width 0.254)
						(type default)
					)
					(fill
						(type none)
					)
				)
				(polyline
					(pts
						(xy 7.366 2.286) (xy 7.874 3.048) (xy 6.858 3.048) (xy 7.366 2.286)
					)
					(stroke
						(width 0.254)
						(type default)
					)
					(fill
						(type outline)
					)
				)
				(polyline
					(pts
						(xy 7.874 2.286) (xy 6.858 2.286)
					)
					(stroke
						(width 0.254)
						(type default)
					)
					(fill
						(type background)
					)
				)
				(pin bidirectional line
					(at 0 0 0)
					(length 2.54)
					(name "G"
						(effects
							(font
								(size 1.27 1.27)
							)
						)
					)
					(number "4"
						(effects
							(font
								(size 1.27 1.27)
							)
						)
					)
				)
				(pin bidirectional line
					(at 6.35 7.62 270)
					(length 2.54)
					(name "D"
						(effects
							(font
								(size 1.27 1.27)
							)
						)
					)
					(number "5"
						(effects
							(font
								(size 1.27 1.27)
							)
						)
					)
				)
				(pin bidirectional line
					(at 6.35 -2.54 90)
					(length 2.54)
					(name "S"
						(effects
							(font
								(size 1.27 1.27)
							)
						)
					)
					(number "1"
						(effects
							(font
								(size 1.27 1.27)
							)
						)
					)
				)
				(pin bidirectional line
					(at 6.35 -2.54 90)
					(length 2.54)
					(hide yes)
					(name "S"
						(effects
							(font
								(size 1.27 1.27)
							)
						)
					)
					(number "2"
						(effects
							(font
								(size 1.27 1.27)
							)
						)
					)
				)
				(pin bidirectional line
					(at 6.35 -2.54 90)
					(length 2.54)
					(hide yes)
					(name "S"
						(effects
							(font
								(size 1.27 1.27)
							)
						)
					)
					(number "3"
						(effects
							(font
								(size 1.27 1.27)
							)
						)
					)
				)
			)
		)
	(symbol "antmicroUSBConnectors:USB-Micro-B_WE_629105150521"
			(exclude_from_sim no)
			(in_bom yes)
			(on_board yes)
			(property "Reference" "J"
				(at 24.13 2.54 0)
				(effects
					(font
						(size 1.27 1.27)
						(thickness 0.15)
					)
					(justify left bottom)
				)
			)
			(property "Value" "USB-Micro-B_WE_629105150521"
				(at 24.13 0 0)
				(effects
					(font
						(size 1.27 1.27)
						(thickness 0.15)
					)
					(justify left bottom)
				)
			)
			(property "Footprint" "antmicro-footprints:USB-Micro-B_Receptacle_WE_629105150521"
				(at 24.13 -2.54 0)
				(effects
					(font
						(size 1.27 1.27)
						(thickness 0.15)
					)
					(justify left bottom)
					(hide yes)
				)
			)
			(property "Datasheet" "https://www.we-online.com/components/products/datasheet/629105150521.pdf"
				(at 24.13 -5.08 0)
				(effects
					(font
						(size 1.27 1.27)
						(thickness 0.15)
					)
					(justify left bottom)
					(hide yes)
				)
			)
			(property "Description" "USB - micro B USB 2.0 Receptacle Connector 5 Position Surface Mount, Right Angle"
				(at 0 0 0)
				(effects
					(font
						(size 1.27 1.27)
					)
					(hide yes)
				)
			)
			(property "MPN" "629105150521"
				(at 24.13 -7.62 0)
				(effects
					(font
						(size 1.27 1.27)
						(thickness 0.15)
					)
					(justify left bottom)
					(hide yes)
				)
			)
			(property "Manufacturer" "Würth Elektronik"
				(at 24.13 -10.16 0)
				(effects
					(font
						(size 1.27 1.27)
						(thickness 0.15)
					)
					(justify left bottom)
					(hide yes)
				)
			)
			(property "Author" "Antmicro"
				(at 24.13 -12.7 0)
				(effects
					(font
						(size 1.27 1.27)
						(thickness 0.15)
					)
					(justify left bottom)
					(hide yes)
				)
			)
			(property "License" "Apache-2.0"
				(at 24.13 -15.24 0)
				(effects
					(font
						(size 1.27 1.27)
						(thickness 0.15)
					)
					(justify left bottom)
					(hide yes)
				)
			)
			(property "ki_keywords" "USB, MICRO, CONNECTOR, SMT, HORIZONTAL"
				(at 0 0 0)
				(effects
					(font
						(size 1.27 1.27)
					)
					(hide yes)
				)
			)
			(symbol "USB-Micro-B_WE_629105150521_0_1"
				(polyline
					(pts
						(xy -13.97 -5.715) (xy -15.24 -6.985) (xy -15.24 -12.7)
					)
					(stroke
						(width 0.254)
						(type default)
					)
					(fill
						(type none)
					)
				)
				(polyline
					(pts
						(xy -13.97 -13.97) (xy -15.24 -12.7)
					)
					(stroke
						(width 0.254)
						(type default)
					)
					(fill
						(type none)
					)
				)
				(rectangle
					(start -13.335 -7.366)
					(end -13.97 -12.446)
					(stroke
						(width 0.127)
						(type default)
					)
					(fill
						(type outline)
					)
				)
				(polyline
					(pts
						(xy -12.7 -5.715) (xy -13.97 -5.715)
					)
					(stroke
						(width 0.254)
						(type default)
					)
					(fill
						(type none)
					)
				)
				(polyline
					(pts
						(xy -12.7 -13.97) (xy -13.97 -13.97)
					)
					(stroke
						(width 0.254)
						(type default)
					)
					(fill
						(type none)
					)
				)
				(polyline
					(pts
						(xy -12.7 -13.97) (xy -12.7 -5.715)
					)
					(stroke
						(width 0.254)
						(type default)
					)
					(fill
						(type none)
					)
				)
			)
			(symbol "USB-Micro-B_WE_629105150521_1_1"
				(rectangle
					(start -21.59 2.54)
					(end -2.54 -22.86)
					(stroke
						(width 0.254)
						(type default)
					)
					(fill
						(type background)
					)
				)
				(circle
					(center -18.796 -10.414)
					(radius 0.284)
					(stroke
						(width 0.254)
						(type default)
					)
					(fill
						(type outline)
					)
				)
				(polyline
					(pts
						(xy -18.542 -8.763) (xy -17.907 -7.62) (xy -17.272 -8.763) (xy -18.542 -8.763)
					)
					(stroke
						(width 0.254)
						(type default)
					)
					(fill
						(type outline)
					)
				)
				(polyline
					(pts
						(xy -17.907 -11.938) (xy -17.018 -11.049) (xy -17.018 -10.414)
					)
					(stroke
						(width 0.254)
						(type default)
					)
					(fill
						(type background)
					)
				)
				(polyline
					(pts
						(xy -17.907 -12.319) (xy -18.796 -11.43) (xy -18.796 -10.795)
					)
					(stroke
						(width 0.254)
						(type default)
					)
					(fill
						(type background)
					)
				)
				(polyline
					(pts
						(xy -17.907 -13.081) (xy -17.907 -8.763)
					)
					(stroke
						(width 0.254)
						(type default)
					)
					(fill
						(type background)
					)
				)
				(circle
					(center -17.907 -13.208)
					(radius 0.5236)
					(stroke
						(width 0.254)
						(type default)
					)
					(fill
						(type outline)
					)
				)
				(rectangle
					(start -17.399 -10.414)
					(end -16.637 -9.652)
					(stroke
						(width 0.254)
						(type default)
					)
					(fill
						(type outline)
					)
				)
				(pin passive line
					(at 0 0 180)
					(length 2.54)
					(name "VBUS"
						(effects
							(font
								(size 1.27 1.27)
							)
						)
					)
					(number "1"
						(effects
							(font
								(size 1.27 1.27)
							)
						)
					)
				)
				(pin bidirectional line
					(at 0 -5.08 180)
					(length 2.54)
					(name "D+"
						(effects
							(font
								(size 1.27 1.27)
							)
						)
					)
					(number "3"
						(effects
							(font
								(size 1.27 1.27)
							)
						)
					)
				)
				(pin bidirectional line
					(at 0 -7.62 180)
					(length 2.54)
					(name "D-"
						(effects
							(font
								(size 1.27 1.27)
							)
						)
					)
					(number "2"
						(effects
							(font
								(size 1.27 1.27)
							)
						)
					)
				)
				(pin bidirectional line
					(at 0 -12.7 180)
					(length 2.54)
					(name "ID"
						(effects
							(font
								(size 1.27 1.27)
							)
						)
					)
					(number "4"
						(effects
							(font
								(size 1.27 1.27)
							)
						)
					)
				)
				(pin power_in line
					(at 0 -17.78 180)
					(length 2.54)
					(name "GND"
						(effects
							(font
								(size 1.27 1.27)
							)
						)
					)
					(number "5"
						(effects
							(font
								(size 1.27 1.27)
							)
						)
					)
				)
				(pin passive line
					(at 0 -20.32 180)
					(length 2.54)
					(name "SHIELD"
						(effects
							(font
								(size 1.27 1.27)
							)
						)
					)
					(number "SH"
						(effects
							(font
								(size 1.27 1.27)
							)
						)
					)
				)
			)
		)
	(symbol "antmicroVideoConnectors:HDMI-A_WE_685119134923"
			(exclude_from_sim no)
			(in_bom yes)
			(on_board yes)
			(property "Reference" "J"
				(at 35.56 -2.54 0)
				(effects
					(font
						(size 1.27 1.27)
						(thickness 0.15)
					)
					(justify left bottom)
				)
			)
			(property "Value" "HDMI-A_WE_685119134923"
				(at 35.56 -5.08 0)
				(effects
					(font
						(size 1.27 1.27)
						(thickness 0.15)
					)
					(justify left bottom)
				)
			)
			(property "Footprint" "antmicro-footprints:HDMI-A_Receptacle_WE_685119134923"
				(at 35.56 -7.62 0)
				(effects
					(font
						(size 1.27 1.27)
						(thickness 0.15)
					)
					(justify left bottom)
					(hide yes)
				)
			)
			(property "Datasheet" "https://www.we-online.com/components/products/datasheet/685119134923.pdf"
				(at 35.56 -10.16 0)
				(effects
					(font
						(size 1.27 1.27)
						(thickness 0.15)
					)
					(justify left bottom)
					(hide yes)
				)
			)
			(property "Description" "HDMI Receptacle Connector 19 Position Surface Mount, Right Angle; Through Hole"
				(at 0 0 0)
				(effects
					(font
						(size 1.27 1.27)
					)
					(hide yes)
				)
			)
			(property "MPN" "685119134923"
				(at 35.56 -12.7 0)
				(effects
					(font
						(size 1.27 1.27)
						(thickness 0.15)
					)
					(justify left bottom)
					(hide yes)
				)
			)
			(property "Manufacturer" "Würth Elektronik"
				(at 35.56 -15.24 0)
				(effects
					(font
						(size 1.27 1.27)
						(thickness 0.15)
					)
					(justify left bottom)
					(hide yes)
				)
			)
			(property "Author" "Antmicro"
				(at 35.56 -17.78 0)
				(effects
					(font
						(size 1.27 1.27)
						(thickness 0.15)
					)
					(justify left bottom)
					(hide yes)
				)
			)
			(property "License" "Apache-2.0"
				(at 35.56 -20.32 0)
				(effects
					(font
						(size 1.27 1.27)
						(thickness 0.15)
					)
					(justify left bottom)
					(hide yes)
				)
			)
			(property "ki_keywords" "HDMI, CONNECTOR, THT"
				(at 0 0 0)
				(effects
					(font
						(size 1.27 1.27)
					)
					(hide yes)
				)
			)
			(property "ki_fp_filters" "685119134923"
				(at 0 0 0)
				(effects
					(font
						(size 1.27 1.27)
					)
					(hide yes)
				)
			)
			(symbol "HDMI-A_WE_685119134923_0_0"
				(polyline
					(pts
						(xy 13.97 0) (xy 13.97 1.524) (xy 13.97 0.762) (xy 15.875 0.762) (xy 15.875 1.524) (xy 15.875 0)
					)
					(stroke
						(width 0.635)
						(type default)
					)
					(fill
						(type none)
					)
				)
				(polyline
					(pts
						(xy 16.637 1.524) (xy 18.288 1.524) (xy 18.542 1.27) (xy 18.542 0.254) (xy 18.288 0) (xy 16.637 0)
						(xy 16.637 0.762)
					)
					(stroke
						(width 0.635)
						(type default)
					)
					(fill
						(type none)
					)
				)
				(polyline
					(pts
						(xy 22.098 0) (xy 22.098 1.524)
					)
					(stroke
						(width 0.635)
						(type default)
					)
					(fill
						(type none)
					)
				)
			)
			(symbol "HDMI-A_WE_685119134923_0_1"
				(polyline
					(pts
						(xy 10.16 -15.24) (xy 13.97 -15.24) (xy 15.875 -17.145) (xy 15.875 -28.575) (xy 13.97 -30.48)
						(xy 10.16 -30.48) (xy 10.16 -15.24)
					)
					(stroke
						(width 0.635)
						(type default)
					)
					(fill
						(type none)
					)
				)
				(polyline
					(pts
						(xy 12.065 -16.51) (xy 13.335 -16.51) (xy 13.97 -17.145) (xy 13.97 -28.575) (xy 13.335 -29.21)
						(xy 12.065 -29.21) (xy 12.065 -16.51)
					)
					(stroke
						(width 0.254)
						(type default)
					)
					(fill
						(type outline)
					)
				)
				(polyline
					(pts
						(xy 19.304 0) (xy 19.304 1.524) (xy 20.32 1.524) (xy 20.32 0) (xy 20.32 1.524) (xy 21.082 1.524)
						(xy 21.336 1.27) (xy 21.336 0)
					)
					(stroke
						(width 0.635)
						(type default)
					)
					(fill
						(type none)
					)
				)
			)
			(symbol "HDMI-A_WE_685119134923_1_1"
				(rectangle
					(start 2.54 2.54)
					(end 22.86 -53.34)
					(stroke
						(width 0.254)
						(type default)
					)
					(fill
						(type background)
					)
				)
				(pin bidirectional line
					(at 0 0 0)
					(length 2.54)
					(name "D2+"
						(effects
							(font
								(size 1.27 1.27)
							)
						)
					)
					(number "1"
						(effects
							(font
								(size 1.27 1.27)
							)
						)
					)
				)
				(pin bidirectional line
					(at 0 -2.54 0)
					(length 2.54)
					(name "D2-"
						(effects
							(font
								(size 1.27 1.27)
							)
						)
					)
					(number "3"
						(effects
							(font
								(size 1.27 1.27)
							)
						)
					)
				)
				(pin bidirectional line
					(at 0 -7.62 0)
					(length 2.54)
					(name "D1+"
						(effects
							(font
								(size 1.27 1.27)
							)
						)
					)
					(number "4"
						(effects
							(font
								(size 1.27 1.27)
							)
						)
					)
				)
				(pin bidirectional line
					(at 0 -10.16 0)
					(length 2.54)
					(name "D1-"
						(effects
							(font
								(size 1.27 1.27)
							)
						)
					)
					(number "6"
						(effects
							(font
								(size 1.27 1.27)
							)
						)
					)
				)
				(pin bidirectional line
					(at 0 -15.24 0)
					(length 2.54)
					(name "D0+"
						(effects
							(font
								(size 1.27 1.27)
							)
						)
					)
					(number "7"
						(effects
							(font
								(size 1.27 1.27)
							)
						)
					)
				)
				(pin bidirectional line
					(at 0 -17.78 0)
					(length 2.54)
					(name "D0-"
						(effects
							(font
								(size 1.27 1.27)
							)
						)
					)
					(number "9"
						(effects
							(font
								(size 1.27 1.27)
							)
						)
					)
				)
				(pin bidirectional line
					(at 0 -22.86 0)
					(length 2.54)
					(name "CK+"
						(effects
							(font
								(size 1.27 1.27)
							)
						)
					)
					(number "10"
						(effects
							(font
								(size 1.27 1.27)
							)
						)
					)
				)
				(pin bidirectional line
					(at 0 -25.4 0)
					(length 2.54)
					(name "CK-"
						(effects
							(font
								(size 1.27 1.27)
							)
						)
					)
					(number "12"
						(effects
							(font
								(size 1.27 1.27)
							)
						)
					)
				)
				(pin bidirectional line
					(at 0 -30.48 0)
					(length 2.54)
					(name "SCL"
						(effects
							(font
								(size 1.27 1.27)
							)
						)
					)
					(number "15"
						(effects
							(font
								(size 1.27 1.27)
							)
						)
					)
				)
				(pin bidirectional line
					(at 0 -33.02 0)
					(length 2.54)
					(name "SDA"
						(effects
							(font
								(size 1.27 1.27)
							)
						)
					)
					(number "16"
						(effects
							(font
								(size 1.27 1.27)
							)
						)
					)
				)
				(pin bidirectional line
					(at 0 -38.1 0)
					(length 2.54)
					(name "CEC"
						(effects
							(font
								(size 1.27 1.27)
							)
						)
					)
					(number "13"
						(effects
							(font
								(size 1.27 1.27)
							)
						)
					)
				)
				(pin bidirectional line
					(at 0 -43.18 0)
					(length 2.54)
					(name "HPD/HEAC-"
						(effects
							(font
								(size 1.27 1.27)
							)
						)
					)
					(number "19"
						(effects
							(font
								(size 1.27 1.27)
							)
						)
					)
					(alternate "HEAC-" passive line)
					(alternate "HPD" passive line)
				)
				(pin bidirectional line
					(at 0 -45.72 0)
					(length 2.54)
					(name "UTILITY/HEAC+"
						(effects
							(font
								(size 1.27 1.27)
							)
						)
					)
					(number "14"
						(effects
							(font
								(size 1.27 1.27)
							)
						)
					)
					(alternate "HEAC+" passive line)
					(alternate "UTILITY" passive line)
				)
				(pin power_in line
					(at 0 -50.8 0)
					(length 2.54)
					(name "+5V"
						(effects
							(font
								(size 1.27 1.27)
							)
						)
					)
					(number "18"
						(effects
							(font
								(size 1.27 1.27)
							)
						)
					)
				)
				(pin passive line
					(at 25.4 -38.1 180)
					(length 2.54)
					(name "D2S"
						(effects
							(font
								(size 1.27 1.27)
							)
						)
					)
					(number "2"
						(effects
							(font
								(size 1.27 1.27)
							)
						)
					)
				)
				(pin passive line
					(at 25.4 -40.64 180)
					(length 2.54)
					(name "D1S"
						(effects
							(font
								(size 1.27 1.27)
							)
						)
					)
					(number "5"
						(effects
							(font
								(size 1.27 1.27)
							)
						)
					)
				)
				(pin passive line
					(at 25.4 -43.18 180)
					(length 2.54)
					(name "D0S"
						(effects
							(font
								(size 1.27 1.27)
							)
						)
					)
					(number "8"
						(effects
							(font
								(size 1.27 1.27)
							)
						)
					)
				)
				(pin passive line
					(at 25.4 -45.72 180)
					(length 2.54)
					(name "CKS"
						(effects
							(font
								(size 1.27 1.27)
							)
						)
					)
					(number "11"
						(effects
							(font
								(size 1.27 1.27)
							)
						)
					)
				)
				(pin power_in line
					(at 25.4 -48.26 180)
					(length 2.54)
					(name "GND"
						(effects
							(font
								(size 1.27 1.27)
							)
						)
					)
					(number "17"
						(effects
							(font
								(size 1.27 1.27)
							)
						)
					)
				)
				(pin passive line
					(at 25.4 -50.8 180)
					(length 2.54)
					(name "SH"
						(effects
							(font
								(size 1.27 1.27)
							)
						)
					)
					(number "SH"
						(effects
							(font
								(size 1.27 1.27)
							)
						)
					)
				)
			)
		)
	(symbol "antmicropower:GND"
			(power)
			(pin_numbers
				(hide yes)
			)
			(pin_names
				(hide yes)
			)
			(exclude_from_sim no)
			(in_bom yes)
			(on_board yes)
			(property "Reference" "#PWR"
				(at 8.89 -2.54 0)
				(effects
					(font
						(size 1.27 1.27)
						(thickness 0.15)
					)
					(justify left bottom)
					(hide yes)
				)
			)
			(property "Value" "GND"
				(at 8.89 -5.08 0)
				(effects
					(font
						(size 1.27 1.27)
						(thickness 0.15)
					)
					(justify left bottom)
				)
			)
			(property "Footprint" ""
				(at 8.89 -7.62 0)
				(effects
					(font
						(size 1.27 1.27)
						(thickness 0.15)
					)
					(justify left bottom)
					(hide yes)
				)
			)
			(property "Datasheet" ""
				(at 8.89 -12.7 0)
				(effects
					(font
						(size 1.27 1.27)
						(thickness 0.15)
					)
					(justify left bottom)
					(hide yes)
				)
			)
			(property "Description" ""
				(at 0 0 0)
				(effects
					(font
						(size 1.27 1.27)
					)
					(hide yes)
				)
			)
			(property "Author" "Antmicro"
				(at 8.89 -7.62 0)
				(effects
					(font
						(size 1.27 1.27)
						(thickness 0.15)
					)
					(justify left bottom)
					(hide yes)
				)
			)
			(property "License" "Apache-2.0"
				(at 8.89 -10.16 0)
				(effects
					(font
						(size 1.27 1.27)
						(thickness 0.15)
					)
					(justify left bottom)
					(hide yes)
				)
			)
			(symbol "GND_1_1"
				(polyline
					(pts
						(xy 0 0) (xy 0 -1.27) (xy 1.27 -1.27) (xy 0 -2.54) (xy -1.27 -1.27) (xy 0 -1.27)
					)
					(stroke
						(width 0)
						(type default)
					)
					(fill
						(type none)
					)
				)
				(pin power_in line
					(at 0 0 270)
					(length 0)
					(name "GND"
						(effects
							(font
								(size 1.27 1.27)
							)
						)
					)
					(number "1"
						(effects
							(font
								(size 1.27 1.27)
							)
						)
					)
				)
			)
		)
)
